FILE_TYPE = MACRO_DRAWING;
SET COLOR_WIRE YELLOW;
SET COLOR_PROP ORANGE;
SET COLOR_DOT WHITE;
SET COLOR_ARC YELLOW;
SET COLOR_BODY GREEN;
SET COLOR_NOTE PURPLE;
SET PROP_DISPLAY VALUE;
SET PAGE_NUMBER P21;
FORCEADD GENOA_SP5..35
(-4500 3625);
FORCEPROP 1 LAST LOCATION U25
J 0
(-5145 6456);
DISPLAY 0.489362 (-5145 6456);
PAINT SKYBLUE (-5145 6456);
FORCEPROP 0 LAST $SEC 35
J 0
(-5125 6500);
DISPLAY 0.680851 (-5125 6500);
PAINT MONO (-5125 6500);
DISPLAY INVISIBLE (-5125 6500);
FORCEPROP 0 LAST CDS_SEC 35
J 0
(-5150 6450);
DISPLAY 1.021277 (-5150 6450);
DISPLAY INVISIBLE (-5150 6450);
FORCEPROP 0 LASTPIN (-5300 3000) $PN BC9
J 2
(-5310 3010);
DISPLAY 0.489362 (-5310 3010);
PAINT MONO (-5310 3010);
FORCEPROP 0 LASTPIN (-5300 2950) $PN BD9
J 2
(-5310 2960);
DISPLAY 0.489362 (-5310 2960);
PAINT MONO (-5310 2960);
FORCEPROP 0 LASTPIN (-5300 1850) $PN BF9
J 2
(-5310 1860);
DISPLAY 0.489362 (-5310 1860);
PAINT MONO (-5310 1860);
FORCEPROP 0 LASTPIN (-5300 1800) $PN BG9
J 2
(-5310 1810);
DISPLAY 0.489362 (-5310 1810);
PAINT MONO (-5310 1810);
FORCEPROP 0 LASTPIN (-5300 2150) $PN AT11
J 2
(-5310 2160);
DISPLAY 0.489362 (-5310 2160);
PAINT MONO (-5310 2160);
FORCEPROP 0 LASTPIN (-5300 2050) $PN AU10
J 2
(-5310 2060);
DISPLAY 0.489362 (-5310 2060);
PAINT MONO (-5310 2060);
FORCEPROP 0 LASTPIN (-5300 2850) $PN AU9
J 2
(-5310 2860);
DISPLAY 0.489362 (-5310 2860);
PAINT MONO (-5310 2860);
FORCEPROP 0 LASTPIN (-5300 2800) $PN AV11
J 2
(-5310 2810);
DISPLAY 0.489362 (-5310 2810);
PAINT MONO (-5310 2810);
FORCEPROP 0 LASTPIN (-5300 2700) $PN BN10
J 2
(-5310 2710);
DISPLAY 0.489362 (-5310 2710);
PAINT MONO (-5310 2710);
FORCEPROP 0 LASTPIN (-5300 1700) $PN AV9
J 2
(-5310 1710);
DISPLAY 0.489362 (-5310 1710);
PAINT MONO (-5310 1710);
FORCEPROP 0 LASTPIN (-5300 1650) $PN AW10
J 2
(-5310 1660);
DISPLAY 0.489362 (-5310 1660);
PAINT MONO (-5310 1660);
FORCEPROP 0 LASTPIN (-5300 1550) $PN BP11
J 2
(-5310 1560);
DISPLAY 0.489362 (-5310 1560);
PAINT MONO (-5310 1560);
FORCEPROP 0 LASTPIN (-5300 3850) $PN AW9
J 2
(-5310 3860);
DISPLAY 0.489362 (-5310 3860);
PAINT MONO (-5310 3860);
FORCEPROP 0 LASTPIN (-5300 3800) $PN AY9
J 2
(-5310 3810);
DISPLAY 0.489362 (-5310 3810);
PAINT MONO (-5310 3810);
FORCEPROP 0 LASTPIN (-5300 3750) $PN AY11
J 2
(-5310 3760);
DISPLAY 0.489362 (-5310 3760);
PAINT MONO (-5310 3760);
FORCEPROP 0 LASTPIN (-5300 3700) $PN BA10
J 2
(-5310 3710);
DISPLAY 0.489362 (-5310 3710);
PAINT MONO (-5310 3710);
FORCEPROP 0 LASTPIN (-5300 3650) $PN BA9
J 2
(-5310 3660);
DISPLAY 0.489362 (-5310 3660);
PAINT MONO (-5310 3660);
FORCEPROP 0 LASTPIN (-5300 3600) $PN BB9
J 2
(-5310 3610);
DISPLAY 0.489362 (-5310 3610);
PAINT MONO (-5310 3610);
FORCEPROP 0 LASTPIN (-5300 3550) $PN BB11
J 2
(-5310 3560);
DISPLAY 0.489362 (-5310 3560);
PAINT MONO (-5310 3560);
FORCEPROP 0 LASTPIN (-3700 2400) $PN AJ9
J 0
(-3690 2410);
DISPLAY 0.489362 (-3690 2410);
PAINT MONO (-3690 2410);
FORCEPROP 0 LASTPIN (-3700 2350) $PN AK11
J 0
(-3690 2360);
DISPLAY 0.489362 (-3690 2360);
PAINT MONO (-3690 2360);
FORCEPROP 0 LASTPIN (-3700 2300) $PN AK9
J 0
(-3690 2310);
DISPLAY 0.489362 (-3690 2310);
PAINT MONO (-3690 2310);
FORCEPROP 0 LASTPIN (-3700 2250) $PN AL10
J 0
(-3690 2260);
DISPLAY 0.489362 (-3690 2260);
PAINT MONO (-3690 2260);
FORCEPROP 0 LASTPIN (-3700 2200) $PN AN9
J 0
(-3690 2210);
DISPLAY 0.489362 (-3690 2210);
PAINT MONO (-3690 2210);
FORCEPROP 0 LASTPIN (-3700 2150) $PN AP11
J 0
(-3690 2160);
DISPLAY 0.489362 (-3690 2160);
PAINT MONO (-3690 2160);
FORCEPROP 0 LASTPIN (-3700 2100) $PN AP9
J 0
(-3690 2110);
DISPLAY 0.489362 (-3690 2110);
PAINT MONO (-3690 2110);
FORCEPROP 0 LASTPIN (-3700 2050) $PN AR10
J 0
(-3690 2060);
DISPLAY 0.489362 (-3690 2060);
PAINT MONO (-3690 2060);
FORCEPROP 0 LASTPIN (-3700 6000) $PN E9
J 0
(-3690 6010);
DISPLAY 0.489362 (-3690 6010);
PAINT MONO (-3690 6010);
FORCEPROP 0 LASTPIN (-3700 5950) $PN F11
J 0
(-3690 5960);
DISPLAY 0.489362 (-3690 5960);
PAINT MONO (-3690 5960);
FORCEPROP 0 LASTPIN (-3700 5900) $PN F9
J 0
(-3690 5910);
DISPLAY 0.489362 (-3690 5910);
PAINT MONO (-3690 5910);
FORCEPROP 0 LASTPIN (-3700 5850) $PN G10
J 0
(-3690 5860);
DISPLAY 0.489362 (-3690 5860);
PAINT MONO (-3690 5860);
FORCEPROP 0 LASTPIN (-3700 5800) $PN J9
J 0
(-3690 5810);
DISPLAY 0.489362 (-3690 5810);
PAINT MONO (-3690 5810);
FORCEPROP 0 LASTPIN (-3700 5750) $PN K11
J 0
(-3690 5760);
DISPLAY 0.489362 (-3690 5760);
PAINT MONO (-3690 5760);
FORCEPROP 0 LASTPIN (-3700 5700) $PN K9
J 0
(-3690 5710);
DISPLAY 0.489362 (-3690 5710);
PAINT MONO (-3690 5710);
FORCEPROP 0 LASTPIN (-3700 5650) $PN L10
J 0
(-3690 5660);
DISPLAY 0.489362 (-3690 5660);
PAINT MONO (-3690 5660);
FORCEPROP 0 LASTPIN (-3700 5550) $PN L9
J 0
(-3690 5560);
DISPLAY 0.489362 (-3690 5560);
PAINT MONO (-3690 5560);
FORCEPROP 0 LASTPIN (-3700 5500) $PN M11
J 0
(-3690 5510);
DISPLAY 0.489362 (-3690 5510);
PAINT MONO (-3690 5510);
FORCEPROP 0 LASTPIN (-3700 5450) $PN M9
J 0
(-3690 5460);
DISPLAY 0.489362 (-3690 5460);
PAINT MONO (-3690 5460);
FORCEPROP 0 LASTPIN (-3700 5400) $PN N10
J 0
(-3690 5410);
DISPLAY 0.489362 (-3690 5410);
PAINT MONO (-3690 5410);
FORCEPROP 0 LASTPIN (-3700 5350) $PN R9
J 0
(-3690 5360);
DISPLAY 0.489362 (-3690 5360);
PAINT MONO (-3690 5360);
FORCEPROP 0 LASTPIN (-3700 5300) $PN T11
J 0
(-3690 5310);
DISPLAY 0.489362 (-3690 5310);
PAINT MONO (-3690 5310);
FORCEPROP 0 LASTPIN (-3700 5250) $PN T9
J 0
(-3690 5260);
DISPLAY 0.489362 (-3690 5260);
PAINT MONO (-3690 5260);
FORCEPROP 0 LASTPIN (-3700 5200) $PN U10
J 0
(-3690 5210);
DISPLAY 0.489362 (-3690 5210);
PAINT MONO (-3690 5210);
FORCEPROP 0 LASTPIN (-3700 5100) $PN U9
J 0
(-3690 5110);
DISPLAY 0.489362 (-3690 5110);
PAINT MONO (-3690 5110);
FORCEPROP 0 LASTPIN (-3700 5050) $PN V11
J 0
(-3690 5060);
DISPLAY 0.489362 (-3690 5060);
PAINT MONO (-3690 5060);
FORCEPROP 0 LASTPIN (-3700 5000) $PN V9
J 0
(-3690 5010);
DISPLAY 0.489362 (-3690 5010);
PAINT MONO (-3690 5010);
FORCEPROP 0 LASTPIN (-3700 4950) $PN W10
J 0
(-3690 4960);
DISPLAY 0.489362 (-3690 4960);
PAINT MONO (-3690 4960);
FORCEPROP 0 LASTPIN (-3700 4900) $PN AA9
J 0
(-3690 4910);
DISPLAY 0.489362 (-3690 4910);
PAINT MONO (-3690 4910);
FORCEPROP 0 LASTPIN (-3700 4850) $PN AB11
J 0
(-3690 4860);
DISPLAY 0.489362 (-3690 4860);
PAINT MONO (-3690 4860);
FORCEPROP 0 LASTPIN (-3700 4800) $PN AB9
J 0
(-3690 4810);
DISPLAY 0.489362 (-3690 4810);
PAINT MONO (-3690 4810);
FORCEPROP 0 LASTPIN (-3700 4750) $PN AC10
J 0
(-3690 4760);
DISPLAY 0.489362 (-3690 4760);
PAINT MONO (-3690 4760);
FORCEPROP 0 LASTPIN (-3700 4650) $PN AC9
J 0
(-3690 4660);
DISPLAY 0.489362 (-3690 4660);
PAINT MONO (-3690 4660);
FORCEPROP 0 LASTPIN (-3700 4600) $PN AD11
J 0
(-3690 4610);
DISPLAY 0.489362 (-3690 4610);
PAINT MONO (-3690 4610);
FORCEPROP 0 LASTPIN (-3700 4550) $PN AD9
J 0
(-3690 4560);
DISPLAY 0.489362 (-3690 4560);
PAINT MONO (-3690 4560);
FORCEPROP 0 LASTPIN (-3700 4500) $PN AE10
J 0
(-3690 4510);
DISPLAY 0.489362 (-3690 4510);
PAINT MONO (-3690 4510);
FORCEPROP 0 LASTPIN (-3700 4450) $PN AG9
J 0
(-3690 4460);
DISPLAY 0.489362 (-3690 4460);
PAINT MONO (-3690 4460);
FORCEPROP 0 LASTPIN (-3700 4400) $PN AH11
J 0
(-3690 4410);
DISPLAY 0.489362 (-3690 4410);
PAINT MONO (-3690 4410);
FORCEPROP 0 LASTPIN (-3700 4350) $PN AH9
J 0
(-3690 4360);
DISPLAY 0.489362 (-3690 4360);
PAINT MONO (-3690 4360);
FORCEPROP 0 LASTPIN (-3700 4300) $PN AJ10
J 0
(-3690 4310);
DISPLAY 0.489362 (-3690 4310);
PAINT MONO (-3690 4310);
FORCEPROP 0 LASTPIN (-5300 6000) $PN G9
J 2
(-5310 6010);
DISPLAY 0.489362 (-5310 6010);
PAINT MONO (-5310 6010);
FORCEPROP 0 LASTPIN (-5300 5900) $PN N9
J 2
(-5310 5910);
DISPLAY 0.489362 (-5310 5910);
PAINT MONO (-5310 5910);
FORCEPROP 0 LASTPIN (-5300 5800) $PN W9
J 2
(-5310 5810);
DISPLAY 0.489362 (-5310 5810);
PAINT MONO (-5310 5810);
FORCEPROP 0 LASTPIN (-5300 5700) $PN AE9
J 2
(-5310 5710);
DISPLAY 0.489362 (-5310 5710);
PAINT MONO (-5310 5710);
FORCEPROP 0 LASTPIN (-5300 5600) $PN AL9
J 2
(-5310 5610);
DISPLAY 0.489362 (-5310 5610);
PAINT MONO (-5310 5610);
FORCEPROP 0 LASTPIN (-5300 5500) $PN J10
J 2
(-5310 5510);
DISPLAY 0.489362 (-5310 5510);
PAINT MONO (-5310 5510);
FORCEPROP 0 LASTPIN (-5300 5400) $PN R10
J 2
(-5310 5410);
DISPLAY 0.489362 (-5310 5410);
PAINT MONO (-5310 5410);
FORCEPROP 0 LASTPIN (-5300 5300) $PN AA10
J 2
(-5310 5310);
DISPLAY 0.489362 (-5310 5310);
PAINT MONO (-5310 5310);
FORCEPROP 0 LASTPIN (-5300 5200) $PN AG10
J 2
(-5310 5210);
DISPLAY 0.489362 (-5310 5210);
PAINT MONO (-5310 5210);
FORCEPROP 0 LASTPIN (-5300 5100) $PN AN10
J 2
(-5310 5110);
DISPLAY 0.489362 (-5310 5110);
PAINT MONO (-5310 5110);
FORCEPROP 0 LASTPIN (-5300 5950) $PN H9
J 2
(-5310 5960);
DISPLAY 0.489362 (-5310 5960);
PAINT MONO (-5310 5960);
FORCEPROP 0 LASTPIN (-5300 5850) $PN P9
J 2
(-5310 5860);
DISPLAY 0.489362 (-5310 5860);
PAINT MONO (-5310 5860);
FORCEPROP 0 LASTPIN (-5300 5750) $PN Y9
J 2
(-5310 5760);
DISPLAY 0.489362 (-5310 5760);
PAINT MONO (-5310 5760);
FORCEPROP 0 LASTPIN (-5300 5650) $PN AF9
J 2
(-5310 5660);
DISPLAY 0.489362 (-5310 5660);
PAINT MONO (-5310 5660);
FORCEPROP 0 LASTPIN (-5300 5550) $PN AM9
J 2
(-5310 5560);
DISPLAY 0.489362 (-5310 5560);
PAINT MONO (-5310 5560);
FORCEPROP 0 LASTPIN (-5300 5450) $PN H11
J 2
(-5310 5460);
DISPLAY 0.489362 (-5310 5460);
PAINT MONO (-5310 5460);
FORCEPROP 0 LASTPIN (-5300 5350) $PN P11
J 2
(-5310 5360);
DISPLAY 0.489362 (-5310 5360);
PAINT MONO (-5310 5360);
FORCEPROP 0 LASTPIN (-5300 5250) $PN Y11
J 2
(-5310 5260);
DISPLAY 0.489362 (-5310 5260);
PAINT MONO (-5310 5260);
FORCEPROP 0 LASTPIN (-5300 5150) $PN AF11
J 2
(-5310 5160);
DISPLAY 0.489362 (-5310 5160);
PAINT MONO (-5310 5160);
FORCEPROP 0 LASTPIN (-5300 5050) $PN AM11
J 2
(-5310 5060);
DISPLAY 0.489362 (-5310 5060);
PAINT MONO (-5310 5060);
FORCEPROP 0 LASTPIN (-5300 2600) $PN BC10
J 2
(-5310 2610);
DISPLAY 0.489362 (-5310 2610);
PAINT MONO (-5310 2610);
FORCEPROP 0 LASTPIN (-5300 2500) $PN BM11
J 2
(-5310 2510);
DISPLAY 0.489362 (-5310 2510);
PAINT MONO (-5310 2510);
FORCEPROP 0 LASTPIN (-5300 2450) $PN BN9
J 2
(-5310 2460);
DISPLAY 0.489362 (-5310 2460);
PAINT MONO (-5310 2460);
FORCEPROP 0 LASTPIN (-5300 2350) $PN BP9
J 2
(-5310 2360);
DISPLAY 0.489362 (-5310 2360);
PAINT MONO (-5310 2360);
FORCEPROP 0 LASTPIN (-5300 1450) $PN BL9
J 2
(-5310 1460);
DISPLAY 0.489362 (-5310 1460);
PAINT MONO (-5310 1460);
FORCEPROP 0 LASTPIN (-5300 1400) $PN BM9
J 2
(-5310 1410);
DISPLAY 0.489362 (-5310 1410);
PAINT MONO (-5310 1410);
FORCEPROP 0 LASTPIN (-5300 1300) $PN BR9
J 2
(-5310 1310);
DISPLAY 0.489362 (-5310 1310);
PAINT MONO (-5310 1310);
FORCEPROP 0 LASTPIN (-5300 3450) $PN BG10
J 2
(-5310 3460);
DISPLAY 0.489362 (-5310 3460);
PAINT MONO (-5310 3460);
FORCEPROP 0 LASTPIN (-5300 3400) $PN BH11
J 2
(-5310 3410);
DISPLAY 0.489362 (-5310 3410);
PAINT MONO (-5310 3410);
FORCEPROP 0 LASTPIN (-5300 3350) $PN BH9
J 2
(-5310 3360);
DISPLAY 0.489362 (-5310 3360);
PAINT MONO (-5310 3360);
FORCEPROP 0 LASTPIN (-5300 3300) $PN BJ9
J 2
(-5310 3310);
DISPLAY 0.489362 (-5310 3310);
PAINT MONO (-5310 3310);
FORCEPROP 0 LASTPIN (-5300 3250) $PN BJ10
J 2
(-5310 3260);
DISPLAY 0.489362 (-5310 3260);
PAINT MONO (-5310 3260);
FORCEPROP 0 LASTPIN (-5300 3200) $PN BK11
J 2
(-5310 3210);
DISPLAY 0.489362 (-5310 3210);
PAINT MONO (-5310 3210);
FORCEPROP 0 LASTPIN (-5300 3150) $PN BK9
J 2
(-5310 3160);
DISPLAY 0.489362 (-5310 3160);
PAINT MONO (-5310 3160);
FORCEPROP 0 LASTPIN (-3700 1950) $PN BY9
J 0
(-3690 1960);
DISPLAY 0.489362 (-3690 1960);
PAINT MONO (-3690 1960);
FORCEPROP 0 LASTPIN (-3700 1900) $PN CA10
J 0
(-3690 1910);
DISPLAY 0.489362 (-3690 1910);
PAINT MONO (-3690 1910);
FORCEPROP 0 LASTPIN (-3700 1850) $PN CA9
J 0
(-3690 1860);
DISPLAY 0.489362 (-3690 1860);
PAINT MONO (-3690 1860);
FORCEPROP 0 LASTPIN (-3700 1800) $PN CB11
J 0
(-3690 1810);
DISPLAY 0.489362 (-3690 1810);
PAINT MONO (-3690 1810);
FORCEPROP 0 LASTPIN (-3700 1750) $PN BT9
J 0
(-3690 1760);
DISPLAY 0.489362 (-3690 1760);
PAINT MONO (-3690 1760);
FORCEPROP 0 LASTPIN (-3700 1700) $PN BU10
J 0
(-3690 1710);
DISPLAY 0.489362 (-3690 1710);
PAINT MONO (-3690 1710);
FORCEPROP 0 LASTPIN (-3700 1650) $PN BU9
J 0
(-3690 1660);
DISPLAY 0.489362 (-3690 1660);
PAINT MONO (-3690 1660);
FORCEPROP 0 LASTPIN (-3700 1600) $PN BV11
J 0
(-3690 1610);
DISPLAY 0.489362 (-3690 1610);
PAINT MONO (-3690 1610);
FORCEPROP 0 LASTPIN (-3700 4200) $PN CB9
J 0
(-3690 4210);
DISPLAY 0.489362 (-3690 4210);
PAINT MONO (-3690 4210);
FORCEPROP 0 LASTPIN (-3700 4150) $PN CC10
J 0
(-3690 4160);
DISPLAY 0.489362 (-3690 4160);
PAINT MONO (-3690 4160);
FORCEPROP 0 LASTPIN (-3700 4100) $PN CC9
J 0
(-3690 4110);
DISPLAY 0.489362 (-3690 4110);
PAINT MONO (-3690 4110);
FORCEPROP 0 LASTPIN (-3700 4050) $PN CD11
J 0
(-3690 4060);
DISPLAY 0.489362 (-3690 4060);
PAINT MONO (-3690 4060);
FORCEPROP 0 LASTPIN (-3700 4000) $PN CF9
J 0
(-3690 4010);
DISPLAY 0.489362 (-3690 4010);
PAINT MONO (-3690 4010);
FORCEPROP 0 LASTPIN (-3700 3950) $PN CG10
J 0
(-3690 3960);
DISPLAY 0.489362 (-3690 3960);
PAINT MONO (-3690 3960);
FORCEPROP 0 LASTPIN (-3700 3900) $PN CG9
J 0
(-3690 3910);
DISPLAY 0.489362 (-3690 3910);
PAINT MONO (-3690 3910);
FORCEPROP 0 LASTPIN (-3700 3850) $PN CH11
J 0
(-3690 3860);
DISPLAY 0.489362 (-3690 3860);
PAINT MONO (-3690 3860);
FORCEPROP 0 LASTPIN (-3700 3750) $PN CH9
J 0
(-3690 3760);
DISPLAY 0.489362 (-3690 3760);
PAINT MONO (-3690 3760);
FORCEPROP 0 LASTPIN (-3700 3700) $PN CJ10
J 0
(-3690 3710);
DISPLAY 0.489362 (-3690 3710);
PAINT MONO (-3690 3710);
FORCEPROP 0 LASTPIN (-3700 3650) $PN CJ9
J 0
(-3690 3660);
DISPLAY 0.489362 (-3690 3660);
PAINT MONO (-3690 3660);
FORCEPROP 0 LASTPIN (-3700 3600) $PN CK11
J 0
(-3690 3610);
DISPLAY 0.489362 (-3690 3610);
PAINT MONO (-3690 3610);
FORCEPROP 0 LASTPIN (-3700 3550) $PN CM9
J 0
(-3690 3560);
DISPLAY 0.489362 (-3690 3560);
PAINT MONO (-3690 3560);
FORCEPROP 0 LASTPIN (-3700 3500) $PN CN10
J 0
(-3690 3510);
DISPLAY 0.489362 (-3690 3510);
PAINT MONO (-3690 3510);
FORCEPROP 0 LASTPIN (-3700 3450) $PN CN9
J 0
(-3690 3460);
DISPLAY 0.489362 (-3690 3460);
PAINT MONO (-3690 3460);
FORCEPROP 0 LASTPIN (-3700 3400) $PN CP11
J 0
(-3690 3410);
DISPLAY 0.489362 (-3690 3410);
PAINT MONO (-3690 3410);
FORCEPROP 0 LASTPIN (-3700 3300) $PN CP9
J 0
(-3690 3310);
DISPLAY 0.489362 (-3690 3310);
PAINT MONO (-3690 3310);
FORCEPROP 0 LASTPIN (-3700 3250) $PN CR10
J 0
(-3690 3260);
DISPLAY 0.489362 (-3690 3260);
PAINT MONO (-3690 3260);
FORCEPROP 0 LASTPIN (-3700 3200) $PN CR9
J 0
(-3690 3210);
DISPLAY 0.489362 (-3690 3210);
PAINT MONO (-3690 3210);
FORCEPROP 0 LASTPIN (-3700 3150) $PN CT11
J 0
(-3690 3160);
DISPLAY 0.489362 (-3690 3160);
PAINT MONO (-3690 3160);
FORCEPROP 0 LASTPIN (-3700 3100) $PN CV9
J 0
(-3690 3110);
DISPLAY 0.489362 (-3690 3110);
PAINT MONO (-3690 3110);
FORCEPROP 0 LASTPIN (-3700 3050) $PN CW10
J 0
(-3690 3060);
DISPLAY 0.489362 (-3690 3060);
PAINT MONO (-3690 3060);
FORCEPROP 0 LASTPIN (-3700 3000) $PN CW9
J 0
(-3690 3010);
DISPLAY 0.489362 (-3690 3010);
PAINT MONO (-3690 3010);
FORCEPROP 0 LASTPIN (-3700 2950) $PN CY11
J 0
(-3690 2960);
DISPLAY 0.489362 (-3690 2960);
PAINT MONO (-3690 2960);
FORCEPROP 0 LASTPIN (-3700 2850) $PN CY9
J 0
(-3690 2860);
DISPLAY 0.489362 (-3690 2860);
PAINT MONO (-3690 2860);
FORCEPROP 0 LASTPIN (-3700 2800) $PN DA10
J 0
(-3690 2810);
DISPLAY 0.489362 (-3690 2810);
PAINT MONO (-3690 2810);
FORCEPROP 0 LASTPIN (-3700 2750) $PN DA9
J 0
(-3690 2760);
DISPLAY 0.489362 (-3690 2760);
PAINT MONO (-3690 2760);
FORCEPROP 0 LASTPIN (-3700 2700) $PN DB11
J 0
(-3690 2710);
DISPLAY 0.489362 (-3690 2710);
PAINT MONO (-3690 2710);
FORCEPROP 0 LASTPIN (-3700 2650) $PN DD9
J 0
(-3690 2660);
DISPLAY 0.489362 (-3690 2660);
PAINT MONO (-3690 2660);
FORCEPROP 0 LASTPIN (-3700 2600) $PN DE10
J 0
(-3690 2610);
DISPLAY 0.489362 (-3690 2610);
PAINT MONO (-3690 2610);
FORCEPROP 0 LASTPIN (-3700 2550) $PN DE9
J 0
(-3690 2560);
DISPLAY 0.489362 (-3690 2560);
PAINT MONO (-3690 2560);
FORCEPROP 0 LASTPIN (-3700 2500) $PN DF9
J 0
(-3690 2510);
DISPLAY 0.489362 (-3690 2510);
PAINT MONO (-3690 2510);
FORCEPROP 0 LASTPIN (-5300 4950) $PN CD9
J 2
(-5310 4960);
DISPLAY 0.489362 (-5310 4960);
PAINT MONO (-5310 4960);
FORCEPROP 0 LASTPIN (-5300 4850) $PN CK9
J 2
(-5310 4860);
DISPLAY 0.489362 (-5310 4860);
PAINT MONO (-5310 4860);
FORCEPROP 0 LASTPIN (-5300 4750) $PN CT9
J 2
(-5310 4760);
DISPLAY 0.489362 (-5310 4760);
PAINT MONO (-5310 4760);
FORCEPROP 0 LASTPIN (-5300 4650) $PN DB9
J 2
(-5310 4660);
DISPLAY 0.489362 (-5310 4660);
PAINT MONO (-5310 4660);
FORCEPROP 0 LASTPIN (-5300 4550) $PN BY11
J 2
(-5310 4560);
DISPLAY 0.489362 (-5310 4560);
PAINT MONO (-5310 4560);
FORCEPROP 0 LASTPIN (-5300 4450) $PN CF11
J 2
(-5310 4460);
DISPLAY 0.489362 (-5310 4460);
PAINT MONO (-5310 4460);
FORCEPROP 0 LASTPIN (-5300 4350) $PN CM11
J 2
(-5310 4360);
DISPLAY 0.489362 (-5310 4360);
PAINT MONO (-5310 4360);
FORCEPROP 0 LASTPIN (-5300 4250) $PN CV11
J 2
(-5310 4260);
DISPLAY 0.489362 (-5310 4260);
PAINT MONO (-5310 4260);
FORCEPROP 0 LASTPIN (-5300 4150) $PN DD11
J 2
(-5310 4160);
DISPLAY 0.489362 (-5310 4160);
PAINT MONO (-5310 4160);
FORCEPROP 0 LASTPIN (-5300 4050) $PN BV9
J 2
(-5310 4060);
DISPLAY 0.489362 (-5310 4060);
PAINT MONO (-5310 4060);
FORCEPROP 0 LASTPIN (-5300 4900) $PN CE9
J 2
(-5310 4910);
DISPLAY 0.489362 (-5310 4910);
PAINT MONO (-5310 4910);
FORCEPROP 0 LASTPIN (-5300 4800) $PN CL9
J 2
(-5310 4810);
DISPLAY 0.489362 (-5310 4810);
PAINT MONO (-5310 4810);
FORCEPROP 0 LASTPIN (-5300 4700) $PN CU9
J 2
(-5310 4710);
DISPLAY 0.489362 (-5310 4710);
PAINT MONO (-5310 4710);
FORCEPROP 0 LASTPIN (-5300 4600) $PN DC9
J 2
(-5310 4610);
DISPLAY 0.489362 (-5310 4610);
PAINT MONO (-5310 4610);
FORCEPROP 0 LASTPIN (-5300 4500) $PN BW10
J 2
(-5310 4510);
DISPLAY 0.489362 (-5310 4510);
PAINT MONO (-5310 4510);
FORCEPROP 0 LASTPIN (-5300 4400) $PN CE10
J 2
(-5310 4410);
DISPLAY 0.489362 (-5310 4410);
PAINT MONO (-5310 4410);
FORCEPROP 0 LASTPIN (-5300 4300) $PN CL10
J 2
(-5310 4310);
DISPLAY 0.489362 (-5310 4310);
PAINT MONO (-5310 4310);
FORCEPROP 0 LASTPIN (-5300 4200) $PN CU10
J 2
(-5310 4210);
DISPLAY 0.489362 (-5310 4210);
PAINT MONO (-5310 4210);
FORCEPROP 0 LASTPIN (-5300 4100) $PN DC10
J 2
(-5310 4110);
DISPLAY 0.489362 (-5310 4110);
PAINT MONO (-5310 4110);
FORCEPROP 0 LASTPIN (-5300 4000) $PN BW9
J 2
(-5310 4010);
DISPLAY 0.489362 (-5310 4010);
PAINT MONO (-5310 4010);
FORCEPROP 0 LASTPIN (-5300 2250) $PN BL10
J 2
(-5310 2260);
DISPLAY 0.489362 (-5310 2260);
PAINT MONO (-5310 2260);
FORCEPROP 0 LASTPIN (-5300 1200) $PN BF11
J 2
(-5310 1210);
DISPLAY 0.489362 (-5310 1210);
PAINT MONO (-5310 1210);
FORCEPROP 2 LAST PART_TYPE SMLF
J 0
(-5150 6400);
DISPLAY 1.021277 (-5150 6400);
FORCEPROP 1 LAST MATERIAL IO
J 0
(-5145 6182);
DISPLAY 0.489362 (-5145 6182);
PAINT SKYBLUE (-5145 6182);
FORCEPROP 2 LAST VALUE SOCKET6096_13568-001
J 0
(-5150 6300);
DISPLAY 0.489362 (-5150 6300);
PAINT SKYBLUE (-5150 6300);
FORCEPROP 2 LAST CDS_LIB pure_quanta
J 0
(-4500 3625);
DISPLAY INVISIBLE (-4500 3625);
FORCEPROP 1 LAST CDS_LMAN_SYM_OUTLINE -650,2525,650,-2525
J 0
(-4500 3625);
DISPLAY 0.468085 (-4500 3625);
PAINT GREEN (-4500 3625);
DISPLAY INVISIBLE (-4500 3625);
FORCEPROP 1 LAST NEEDS_NO_SIZE TRUE
J 0
(-4500 3625);
DISPLAY 0.723404 (-4500 3625);
PAINT GREEN (-4500 3625);
DISPLAY INVISIBLE (-4500 3625);
FORCEPROP 1 LAST PATH I159
J 0
(-4500 3625);
DISPLAY 0.723404 (-4500 3625);
PAINT GREEN (-4500 3625);
DISPLAY INVISIBLE (-4500 3625);
FORCEPROP 1 LAST PART_NUMBER DGA^6000030
J 0
(-5145 6309);
DISPLAY 0.489362 (-5145 6309);
PAINT SKYBLUE (-5145 6309);
DISPLAY INVISIBLE (-5145 6309);
FORCEADD OFFPAGE..3
(-2500 6025);
FORCEPROP 2 LAST $XR0 97 
J 0
(-2286 6025);
DISPLAY 0.638298 (-2286 6025);
PAINT MONO (-2286 6025);
FORCEPROP 2 LAST CDS_LIB mstr_standard
J 0
(-2500 6025);
DISPLAY 0.723404 (-2500 6025);
PAINT MONO (-2500 6025);
DISPLAY INVISIBLE (-2500 6025);
FORCEPROP 1 LAST OFFPAGE TRUE
J 0
(-2175 5900);
DISPLAY 0.872340 (-2175 5900);
PAINT GREEN (-2175 5900);
DISPLAY INVISIBLE (-2175 5900);
FORCEPROP 1 LAST COMMENT_BODY TRUE
J 0
(-2550 5925);
DISPLAY 0.872340 (-2550 5925);
PAINT GREEN (-2550 5925);
DISPLAY INVISIBLE (-2550 5925);
FORCEPROP 2 LAST PATH I160
J 0
(-2275 6075);
DISPLAY 1.021277 (-2275 6075);
DISPLAY INVISIBLE (-2275 6075);
FORCEADD OFFPAGE..3
(-2500 4225);
FORCEPROP 2 LAST $XR0 97 
J 0
(-2286 4225);
DISPLAY 0.638298 (-2286 4225);
PAINT MONO (-2286 4225);
FORCEPROP 2 LAST CDS_LIB mstr_standard
J 0
(-2500 4225);
DISPLAY 0.723404 (-2500 4225);
PAINT MONO (-2500 4225);
DISPLAY INVISIBLE (-2500 4225);
FORCEPROP 1 LAST OFFPAGE TRUE
J 0
(-2175 4100);
DISPLAY 0.872340 (-2175 4100);
PAINT GREEN (-2175 4100);
DISPLAY INVISIBLE (-2175 4100);
FORCEPROP 1 LAST COMMENT_BODY TRUE
J 0
(-2550 4125);
DISPLAY 0.872340 (-2550 4125);
PAINT GREEN (-2550 4125);
DISPLAY INVISIBLE (-2550 4125);
FORCEPROP 2 LAST PATH I161
J 0
(-2275 4275);
DISPLAY 1.021277 (-2275 4275);
DISPLAY INVISIBLE (-2275 4275);
FORCEADD TAP..1
(-3225 5950);
FORCEPROP 3 LASTPIN (-3275 5950) SIG_NAME M_L_CPU0_SA_DQ<1>
J 0
(-3265 5960);
DISPLAY 0.659574 (-3265 5960);
PAINT MONO (-3265 5960);
DISPLAY INVISIBLE (-3265 5960);
FORCEPROP 1 LASTPIN (-3275 5950) BN 1
J 0
(-3287 5958);
DISPLAY 0.489362 (-3287 5958);
PAINT GREEN (-3287 5958);
FORCEPROP 2 LAST CDS_LIB mstr_standard
J 0
(-3225 5950);
DISPLAY 0.723404 (-3225 5950);
PAINT MONO (-3225 5950);
DISPLAY INVISIBLE (-3225 5950);
FORCEPROP 1 LAST BODY_TYPE PLUMBING
J 0
(-3225 6000);
DISPLAY 0.872340 (-3225 6000);
PAINT GREEN (-3225 6000);
DISPLAY INVISIBLE (-3225 6000);
FORCEPROP 1 LAST HDL_TAP TRUE
J 0
(-2900 5825);
DISPLAY 0.872340 (-2900 5825);
DISPLAY INVISIBLE (-2900 5825);
FORCEPROP 1 LAST PATH I162
J 0
(-3227 5950);
DISPLAY 0.872340 (-3227 5950);
PAINT GREEN (-3227 5950);
DISPLAY INVISIBLE (-3227 5950);
FORCEADD TAP..1
(-3225 6000);
FORCEPROP 3 LASTPIN (-3275 6000) SIG_NAME M_L_CPU0_SA_DQ<0>
J 0
(-3265 6010);
DISPLAY 0.659574 (-3265 6010);
PAINT MONO (-3265 6010);
DISPLAY INVISIBLE (-3265 6010);
FORCEPROP 1 LASTPIN (-3275 6000) BN 0
J 0
(-3287 6008);
DISPLAY 0.489362 (-3287 6008);
PAINT GREEN (-3287 6008);
FORCEPROP 2 LAST CDS_LIB mstr_standard
J 0
(-3225 6000);
DISPLAY 0.723404 (-3225 6000);
PAINT MONO (-3225 6000);
DISPLAY INVISIBLE (-3225 6000);
FORCEPROP 1 LAST BODY_TYPE PLUMBING
J 0
(-3225 6050);
DISPLAY 0.872340 (-3225 6050);
PAINT GREEN (-3225 6050);
DISPLAY INVISIBLE (-3225 6050);
FORCEPROP 1 LAST HDL_TAP TRUE
J 0
(-2900 5875);
DISPLAY 0.872340 (-2900 5875);
DISPLAY INVISIBLE (-2900 5875);
FORCEPROP 1 LAST PATH I163
J 0
(-3227 6000);
DISPLAY 0.872340 (-3227 6000);
PAINT GREEN (-3227 6000);
DISPLAY INVISIBLE (-3227 6000);
FORCEADD TAP..1
(-3225 5900);
FORCEPROP 3 LASTPIN (-3275 5900) SIG_NAME M_L_CPU0_SA_DQ<2>
J 0
(-3265 5910);
DISPLAY 0.659574 (-3265 5910);
PAINT MONO (-3265 5910);
DISPLAY INVISIBLE (-3265 5910);
FORCEPROP 1 LASTPIN (-3275 5900) BN 2
J 0
(-3287 5908);
DISPLAY 0.489362 (-3287 5908);
PAINT GREEN (-3287 5908);
FORCEPROP 2 LAST CDS_LIB mstr_standard
J 0
(-3225 5900);
DISPLAY 0.723404 (-3225 5900);
PAINT MONO (-3225 5900);
DISPLAY INVISIBLE (-3225 5900);
FORCEPROP 1 LAST BODY_TYPE PLUMBING
J 0
(-3225 5950);
DISPLAY 0.872340 (-3225 5950);
PAINT GREEN (-3225 5950);
DISPLAY INVISIBLE (-3225 5950);
FORCEPROP 1 LAST HDL_TAP TRUE
J 0
(-2900 5775);
DISPLAY 0.872340 (-2900 5775);
DISPLAY INVISIBLE (-2900 5775);
FORCEPROP 1 LAST PATH I164
J 0
(-3227 5900);
DISPLAY 0.872340 (-3227 5900);
PAINT GREEN (-3227 5900);
DISPLAY INVISIBLE (-3227 5900);
FORCEADD TAP..1
(-3225 5850);
FORCEPROP 3 LASTPIN (-3275 5850) SIG_NAME M_L_CPU0_SA_DQ<3>
J 0
(-3265 5860);
DISPLAY 0.659574 (-3265 5860);
PAINT MONO (-3265 5860);
DISPLAY INVISIBLE (-3265 5860);
FORCEPROP 1 LASTPIN (-3275 5850) BN 3
J 0
(-3287 5858);
DISPLAY 0.489362 (-3287 5858);
PAINT GREEN (-3287 5858);
FORCEPROP 2 LAST CDS_LIB mstr_standard
J 0
(-3225 5850);
DISPLAY 0.723404 (-3225 5850);
PAINT MONO (-3225 5850);
DISPLAY INVISIBLE (-3225 5850);
FORCEPROP 1 LAST BODY_TYPE PLUMBING
J 0
(-3225 5900);
DISPLAY 0.872340 (-3225 5900);
PAINT GREEN (-3225 5900);
DISPLAY INVISIBLE (-3225 5900);
FORCEPROP 1 LAST HDL_TAP TRUE
J 0
(-2900 5725);
DISPLAY 0.872340 (-2900 5725);
DISPLAY INVISIBLE (-2900 5725);
FORCEPROP 1 LAST PATH I165
J 0
(-3227 5850);
DISPLAY 0.872340 (-3227 5850);
PAINT GREEN (-3227 5850);
DISPLAY INVISIBLE (-3227 5850);
FORCEADD TAP..1
(-3225 5800);
FORCEPROP 3 LASTPIN (-3275 5800) SIG_NAME M_L_CPU0_SA_DQ<4>
J 0
(-3265 5810);
DISPLAY 0.659574 (-3265 5810);
PAINT MONO (-3265 5810);
DISPLAY INVISIBLE (-3265 5810);
FORCEPROP 1 LASTPIN (-3275 5800) BN 4
J 0
(-3287 5808);
DISPLAY 0.489362 (-3287 5808);
PAINT GREEN (-3287 5808);
FORCEPROP 2 LAST CDS_LIB mstr_standard
J 0
(-3225 5800);
DISPLAY 0.723404 (-3225 5800);
PAINT MONO (-3225 5800);
DISPLAY INVISIBLE (-3225 5800);
FORCEPROP 1 LAST BODY_TYPE PLUMBING
J 0
(-3225 5850);
DISPLAY 0.872340 (-3225 5850);
PAINT GREEN (-3225 5850);
DISPLAY INVISIBLE (-3225 5850);
FORCEPROP 1 LAST HDL_TAP TRUE
J 0
(-2900 5675);
DISPLAY 0.872340 (-2900 5675);
DISPLAY INVISIBLE (-2900 5675);
FORCEPROP 1 LAST PATH I166
J 0
(-3227 5800);
DISPLAY 0.872340 (-3227 5800);
PAINT GREEN (-3227 5800);
DISPLAY INVISIBLE (-3227 5800);
FORCEADD TAP..1
(-3225 5750);
FORCEPROP 3 LASTPIN (-3275 5750) SIG_NAME M_L_CPU0_SA_DQ<5>
J 0
(-3265 5760);
DISPLAY 0.659574 (-3265 5760);
PAINT MONO (-3265 5760);
DISPLAY INVISIBLE (-3265 5760);
FORCEPROP 1 LASTPIN (-3275 5750) BN 5
J 0
(-3287 5758);
DISPLAY 0.489362 (-3287 5758);
PAINT GREEN (-3287 5758);
FORCEPROP 2 LAST CDS_LIB mstr_standard
J 0
(-3225 5750);
DISPLAY 0.723404 (-3225 5750);
PAINT MONO (-3225 5750);
DISPLAY INVISIBLE (-3225 5750);
FORCEPROP 1 LAST BODY_TYPE PLUMBING
J 0
(-3225 5800);
DISPLAY 0.872340 (-3225 5800);
PAINT GREEN (-3225 5800);
DISPLAY INVISIBLE (-3225 5800);
FORCEPROP 1 LAST HDL_TAP TRUE
J 0
(-2900 5625);
DISPLAY 0.872340 (-2900 5625);
DISPLAY INVISIBLE (-2900 5625);
FORCEPROP 1 LAST PATH I167
J 0
(-3227 5750);
DISPLAY 0.872340 (-3227 5750);
PAINT GREEN (-3227 5750);
DISPLAY INVISIBLE (-3227 5750);
FORCEADD TAP..1
(-3225 5700);
FORCEPROP 3 LASTPIN (-3275 5700) SIG_NAME M_L_CPU0_SA_DQ<6>
J 0
(-3265 5710);
DISPLAY 0.659574 (-3265 5710);
PAINT MONO (-3265 5710);
DISPLAY INVISIBLE (-3265 5710);
FORCEPROP 1 LASTPIN (-3275 5700) BN 6
J 0
(-3287 5708);
DISPLAY 0.489362 (-3287 5708);
PAINT GREEN (-3287 5708);
FORCEPROP 2 LAST CDS_LIB mstr_standard
J 0
(-3225 5700);
DISPLAY 0.723404 (-3225 5700);
PAINT MONO (-3225 5700);
DISPLAY INVISIBLE (-3225 5700);
FORCEPROP 1 LAST BODY_TYPE PLUMBING
J 0
(-3225 5750);
DISPLAY 0.872340 (-3225 5750);
PAINT GREEN (-3225 5750);
DISPLAY INVISIBLE (-3225 5750);
FORCEPROP 1 LAST HDL_TAP TRUE
J 0
(-2900 5575);
DISPLAY 0.872340 (-2900 5575);
DISPLAY INVISIBLE (-2900 5575);
FORCEPROP 1 LAST PATH I168
J 0
(-3227 5700);
DISPLAY 0.872340 (-3227 5700);
PAINT GREEN (-3227 5700);
DISPLAY INVISIBLE (-3227 5700);
FORCEADD TAP..1
(-3225 5650);
FORCEPROP 3 LASTPIN (-3275 5650) SIG_NAME M_L_CPU0_SA_DQ<7>
J 0
(-3265 5660);
DISPLAY 0.659574 (-3265 5660);
PAINT MONO (-3265 5660);
DISPLAY INVISIBLE (-3265 5660);
FORCEPROP 1 LASTPIN (-3275 5650) BN 7
J 0
(-3287 5658);
DISPLAY 0.489362 (-3287 5658);
PAINT GREEN (-3287 5658);
FORCEPROP 2 LAST CDS_LIB mstr_standard
J 0
(-3225 5650);
DISPLAY 0.723404 (-3225 5650);
PAINT MONO (-3225 5650);
DISPLAY INVISIBLE (-3225 5650);
FORCEPROP 1 LAST BODY_TYPE PLUMBING
J 0
(-3225 5700);
DISPLAY 0.872340 (-3225 5700);
PAINT GREEN (-3225 5700);
DISPLAY INVISIBLE (-3225 5700);
FORCEPROP 1 LAST HDL_TAP TRUE
J 0
(-2900 5525);
DISPLAY 0.872340 (-2900 5525);
DISPLAY INVISIBLE (-2900 5525);
FORCEPROP 1 LAST PATH I169
J 0
(-3227 5650);
DISPLAY 0.872340 (-3227 5650);
PAINT GREEN (-3227 5650);
DISPLAY INVISIBLE (-3227 5650);
FORCEADD TAP..1
(-3225 5450);
FORCEPROP 3 LASTPIN (-3275 5450) SIG_NAME M_L_CPU0_SA_DQ<10>
J 0
(-3265 5460);
DISPLAY 0.659574 (-3265 5460);
PAINT MONO (-3265 5460);
DISPLAY INVISIBLE (-3265 5460);
FORCEPROP 1 LASTPIN (-3275 5450) BN 10
J 0
(-3287 5458);
DISPLAY 0.489362 (-3287 5458);
PAINT GREEN (-3287 5458);
FORCEPROP 2 LAST CDS_LIB mstr_standard
J 0
(-3225 5450);
DISPLAY 0.723404 (-3225 5450);
PAINT MONO (-3225 5450);
DISPLAY INVISIBLE (-3225 5450);
FORCEPROP 1 LAST BODY_TYPE PLUMBING
J 0
(-3225 5500);
DISPLAY 0.872340 (-3225 5500);
PAINT GREEN (-3225 5500);
DISPLAY INVISIBLE (-3225 5500);
FORCEPROP 1 LAST HDL_TAP TRUE
J 0
(-2900 5325);
DISPLAY 0.872340 (-2900 5325);
DISPLAY INVISIBLE (-2900 5325);
FORCEPROP 1 LAST PATH I170
J 0
(-3227 5450);
DISPLAY 0.872340 (-3227 5450);
PAINT GREEN (-3227 5450);
DISPLAY INVISIBLE (-3227 5450);
FORCEADD TAP..1
(-3225 5500);
FORCEPROP 3 LASTPIN (-3275 5500) SIG_NAME M_L_CPU0_SA_DQ<9>
J 0
(-3265 5510);
DISPLAY 0.659574 (-3265 5510);
PAINT MONO (-3265 5510);
DISPLAY INVISIBLE (-3265 5510);
FORCEPROP 1 LASTPIN (-3275 5500) BN 9
J 0
(-3287 5508);
DISPLAY 0.489362 (-3287 5508);
PAINT GREEN (-3287 5508);
FORCEPROP 2 LAST CDS_LIB mstr_standard
J 0
(-3225 5500);
DISPLAY 0.723404 (-3225 5500);
PAINT MONO (-3225 5500);
DISPLAY INVISIBLE (-3225 5500);
FORCEPROP 1 LAST BODY_TYPE PLUMBING
J 0
(-3225 5550);
DISPLAY 0.872340 (-3225 5550);
PAINT GREEN (-3225 5550);
DISPLAY INVISIBLE (-3225 5550);
FORCEPROP 1 LAST HDL_TAP TRUE
J 0
(-2900 5375);
DISPLAY 0.872340 (-2900 5375);
DISPLAY INVISIBLE (-2900 5375);
FORCEPROP 1 LAST PATH I171
J 0
(-3227 5500);
DISPLAY 0.872340 (-3227 5500);
PAINT GREEN (-3227 5500);
DISPLAY INVISIBLE (-3227 5500);
FORCEADD TAP..1
(-3225 5550);
FORCEPROP 3 LASTPIN (-3275 5550) SIG_NAME M_L_CPU0_SA_DQ<8>
J 0
(-3265 5560);
DISPLAY 0.659574 (-3265 5560);
PAINT MONO (-3265 5560);
DISPLAY INVISIBLE (-3265 5560);
FORCEPROP 1 LASTPIN (-3275 5550) BN 8
J 0
(-3287 5558);
DISPLAY 0.489362 (-3287 5558);
PAINT GREEN (-3287 5558);
FORCEPROP 2 LAST CDS_LIB mstr_standard
J 0
(-3225 5550);
DISPLAY 0.723404 (-3225 5550);
PAINT MONO (-3225 5550);
DISPLAY INVISIBLE (-3225 5550);
FORCEPROP 1 LAST BODY_TYPE PLUMBING
J 0
(-3225 5600);
DISPLAY 0.872340 (-3225 5600);
PAINT GREEN (-3225 5600);
DISPLAY INVISIBLE (-3225 5600);
FORCEPROP 1 LAST HDL_TAP TRUE
J 0
(-2900 5425);
DISPLAY 0.872340 (-2900 5425);
DISPLAY INVISIBLE (-2900 5425);
FORCEPROP 1 LAST PATH I172
J 0
(-3227 5550);
DISPLAY 0.872340 (-3227 5550);
PAINT GREEN (-3227 5550);
DISPLAY INVISIBLE (-3227 5550);
FORCEADD TAP..1
(-3225 5400);
FORCEPROP 3 LASTPIN (-3275 5400) SIG_NAME M_L_CPU0_SA_DQ<11>
J 0
(-3265 5410);
DISPLAY 0.659574 (-3265 5410);
PAINT MONO (-3265 5410);
DISPLAY INVISIBLE (-3265 5410);
FORCEPROP 1 LASTPIN (-3275 5400) BN 11
J 0
(-3287 5408);
DISPLAY 0.489362 (-3287 5408);
PAINT GREEN (-3287 5408);
FORCEPROP 2 LAST CDS_LIB mstr_standard
J 0
(-3225 5400);
DISPLAY 0.723404 (-3225 5400);
PAINT MONO (-3225 5400);
DISPLAY INVISIBLE (-3225 5400);
FORCEPROP 1 LAST BODY_TYPE PLUMBING
J 0
(-3225 5450);
DISPLAY 0.872340 (-3225 5450);
PAINT GREEN (-3225 5450);
DISPLAY INVISIBLE (-3225 5450);
FORCEPROP 1 LAST HDL_TAP TRUE
J 0
(-2900 5275);
DISPLAY 0.872340 (-2900 5275);
DISPLAY INVISIBLE (-2900 5275);
FORCEPROP 1 LAST PATH I173
J 0
(-3227 5400);
DISPLAY 0.872340 (-3227 5400);
PAINT GREEN (-3227 5400);
DISPLAY INVISIBLE (-3227 5400);
FORCEADD TAP..1
(-3225 5300);
FORCEPROP 3 LASTPIN (-3275 5300) SIG_NAME M_L_CPU0_SA_DQ<13>
J 0
(-3265 5310);
DISPLAY 0.659574 (-3265 5310);
PAINT MONO (-3265 5310);
DISPLAY INVISIBLE (-3265 5310);
FORCEPROP 1 LASTPIN (-3275 5300) BN 13
J 0
(-3287 5308);
DISPLAY 0.489362 (-3287 5308);
PAINT GREEN (-3287 5308);
FORCEPROP 2 LAST CDS_LIB mstr_standard
J 0
(-3225 5300);
DISPLAY 0.723404 (-3225 5300);
PAINT MONO (-3225 5300);
DISPLAY INVISIBLE (-3225 5300);
FORCEPROP 1 LAST BODY_TYPE PLUMBING
J 0
(-3225 5350);
DISPLAY 0.872340 (-3225 5350);
PAINT GREEN (-3225 5350);
DISPLAY INVISIBLE (-3225 5350);
FORCEPROP 1 LAST HDL_TAP TRUE
J 0
(-2900 5175);
DISPLAY 0.872340 (-2900 5175);
DISPLAY INVISIBLE (-2900 5175);
FORCEPROP 1 LAST PATH I174
J 0
(-3227 5300);
DISPLAY 0.872340 (-3227 5300);
PAINT GREEN (-3227 5300);
DISPLAY INVISIBLE (-3227 5300);
FORCEADD TAP..1
(-3225 5350);
FORCEPROP 3 LASTPIN (-3275 5350) SIG_NAME M_L_CPU0_SA_DQ<12>
J 0
(-3265 5360);
DISPLAY 0.659574 (-3265 5360);
PAINT MONO (-3265 5360);
DISPLAY INVISIBLE (-3265 5360);
FORCEPROP 1 LASTPIN (-3275 5350) BN 12
J 0
(-3287 5358);
DISPLAY 0.489362 (-3287 5358);
PAINT GREEN (-3287 5358);
FORCEPROP 2 LAST CDS_LIB mstr_standard
J 0
(-3225 5350);
DISPLAY 0.723404 (-3225 5350);
PAINT MONO (-3225 5350);
DISPLAY INVISIBLE (-3225 5350);
FORCEPROP 1 LAST BODY_TYPE PLUMBING
J 0
(-3225 5400);
DISPLAY 0.872340 (-3225 5400);
PAINT GREEN (-3225 5400);
DISPLAY INVISIBLE (-3225 5400);
FORCEPROP 1 LAST HDL_TAP TRUE
J 0
(-2900 5225);
DISPLAY 0.872340 (-2900 5225);
DISPLAY INVISIBLE (-2900 5225);
FORCEPROP 1 LAST PATH I175
J 0
(-3227 5350);
DISPLAY 0.872340 (-3227 5350);
PAINT GREEN (-3227 5350);
DISPLAY INVISIBLE (-3227 5350);
FORCEADD TAP..1
(-3225 5200);
FORCEPROP 3 LASTPIN (-3275 5200) SIG_NAME M_L_CPU0_SA_DQ<15>
J 0
(-3265 5210);
DISPLAY 0.659574 (-3265 5210);
PAINT MONO (-3265 5210);
DISPLAY INVISIBLE (-3265 5210);
FORCEPROP 1 LASTPIN (-3275 5200) BN 15
J 0
(-3287 5208);
DISPLAY 0.489362 (-3287 5208);
PAINT GREEN (-3287 5208);
FORCEPROP 2 LAST CDS_LIB mstr_standard
J 0
(-3225 5200);
DISPLAY 0.723404 (-3225 5200);
PAINT MONO (-3225 5200);
DISPLAY INVISIBLE (-3225 5200);
FORCEPROP 1 LAST BODY_TYPE PLUMBING
J 0
(-3225 5250);
DISPLAY 0.872340 (-3225 5250);
PAINT GREEN (-3225 5250);
DISPLAY INVISIBLE (-3225 5250);
FORCEPROP 1 LAST HDL_TAP TRUE
J 0
(-2900 5075);
DISPLAY 0.872340 (-2900 5075);
DISPLAY INVISIBLE (-2900 5075);
FORCEPROP 1 LAST PATH I176
J 0
(-3227 5200);
DISPLAY 0.872340 (-3227 5200);
PAINT GREEN (-3227 5200);
DISPLAY INVISIBLE (-3227 5200);
FORCEADD TAP..1
(-3225 5250);
FORCEPROP 3 LASTPIN (-3275 5250) SIG_NAME M_L_CPU0_SA_DQ<14>
J 0
(-3265 5260);
DISPLAY 0.659574 (-3265 5260);
PAINT MONO (-3265 5260);
DISPLAY INVISIBLE (-3265 5260);
FORCEPROP 1 LASTPIN (-3275 5250) BN 14
J 0
(-3287 5258);
DISPLAY 0.489362 (-3287 5258);
PAINT GREEN (-3287 5258);
FORCEPROP 2 LAST CDS_LIB mstr_standard
J 0
(-3225 5250);
DISPLAY 0.723404 (-3225 5250);
PAINT MONO (-3225 5250);
DISPLAY INVISIBLE (-3225 5250);
FORCEPROP 1 LAST BODY_TYPE PLUMBING
J 0
(-3225 5300);
DISPLAY 0.872340 (-3225 5300);
PAINT GREEN (-3225 5300);
DISPLAY INVISIBLE (-3225 5300);
FORCEPROP 1 LAST HDL_TAP TRUE
J 0
(-2900 5125);
DISPLAY 0.872340 (-2900 5125);
DISPLAY INVISIBLE (-2900 5125);
FORCEPROP 1 LAST PATH I177
J 0
(-3227 5250);
DISPLAY 0.872340 (-3227 5250);
PAINT GREEN (-3227 5250);
DISPLAY INVISIBLE (-3227 5250);
FORCEADD TAP..1
(-3225 5100);
FORCEPROP 3 LASTPIN (-3275 5100) SIG_NAME M_L_CPU0_SA_DQ<16>
J 0
(-3265 5110);
DISPLAY 0.659574 (-3265 5110);
PAINT MONO (-3265 5110);
DISPLAY INVISIBLE (-3265 5110);
FORCEPROP 1 LASTPIN (-3275 5100) BN 16
J 0
(-3287 5108);
DISPLAY 0.489362 (-3287 5108);
PAINT GREEN (-3287 5108);
FORCEPROP 2 LAST CDS_LIB mstr_standard
J 0
(-3225 5100);
DISPLAY 0.723404 (-3225 5100);
PAINT MONO (-3225 5100);
DISPLAY INVISIBLE (-3225 5100);
FORCEPROP 1 LAST BODY_TYPE PLUMBING
J 0
(-3225 5150);
DISPLAY 0.872340 (-3225 5150);
PAINT GREEN (-3225 5150);
DISPLAY INVISIBLE (-3225 5150);
FORCEPROP 1 LAST HDL_TAP TRUE
J 0
(-2900 4975);
DISPLAY 0.872340 (-2900 4975);
DISPLAY INVISIBLE (-2900 4975);
FORCEPROP 1 LAST PATH I178
J 0
(-3227 5100);
DISPLAY 0.872340 (-3227 5100);
PAINT GREEN (-3227 5100);
DISPLAY INVISIBLE (-3227 5100);
FORCEADD TAP..1
(-3225 5050);
FORCEPROP 3 LASTPIN (-3275 5050) SIG_NAME M_L_CPU0_SA_DQ<17>
J 0
(-3265 5060);
DISPLAY 0.659574 (-3265 5060);
PAINT MONO (-3265 5060);
DISPLAY INVISIBLE (-3265 5060);
FORCEPROP 1 LASTPIN (-3275 5050) BN 17
J 0
(-3287 5058);
DISPLAY 0.489362 (-3287 5058);
PAINT GREEN (-3287 5058);
FORCEPROP 2 LAST CDS_LIB mstr_standard
J 0
(-3225 5050);
DISPLAY 0.723404 (-3225 5050);
PAINT MONO (-3225 5050);
DISPLAY INVISIBLE (-3225 5050);
FORCEPROP 1 LAST BODY_TYPE PLUMBING
J 0
(-3225 5100);
DISPLAY 0.872340 (-3225 5100);
PAINT GREEN (-3225 5100);
DISPLAY INVISIBLE (-3225 5100);
FORCEPROP 1 LAST HDL_TAP TRUE
J 0
(-2900 4925);
DISPLAY 0.872340 (-2900 4925);
DISPLAY INVISIBLE (-2900 4925);
FORCEPROP 1 LAST PATH I179
J 0
(-3227 5050);
DISPLAY 0.872340 (-3227 5050);
PAINT GREEN (-3227 5050);
DISPLAY INVISIBLE (-3227 5050);
FORCEADD TAP..1
(-3225 5000);
FORCEPROP 3 LASTPIN (-3275 5000) SIG_NAME M_L_CPU0_SA_DQ<18>
J 0
(-3265 5010);
DISPLAY 0.659574 (-3265 5010);
PAINT MONO (-3265 5010);
DISPLAY INVISIBLE (-3265 5010);
FORCEPROP 1 LASTPIN (-3275 5000) BN 18
J 0
(-3287 5008);
DISPLAY 0.489362 (-3287 5008);
PAINT GREEN (-3287 5008);
FORCEPROP 2 LAST CDS_LIB mstr_standard
J 0
(-3225 5000);
DISPLAY 0.723404 (-3225 5000);
PAINT MONO (-3225 5000);
DISPLAY INVISIBLE (-3225 5000);
FORCEPROP 1 LAST BODY_TYPE PLUMBING
J 0
(-3225 5050);
DISPLAY 0.872340 (-3225 5050);
PAINT GREEN (-3225 5050);
DISPLAY INVISIBLE (-3225 5050);
FORCEPROP 1 LAST HDL_TAP TRUE
J 0
(-2900 4875);
DISPLAY 0.872340 (-2900 4875);
DISPLAY INVISIBLE (-2900 4875);
FORCEPROP 1 LAST PATH I180
J 0
(-3227 5000);
DISPLAY 0.872340 (-3227 5000);
PAINT GREEN (-3227 5000);
DISPLAY INVISIBLE (-3227 5000);
FORCEADD TAP..1
(-3225 4950);
FORCEPROP 3 LASTPIN (-3275 4950) SIG_NAME M_L_CPU0_SA_DQ<19>
J 0
(-3265 4960);
DISPLAY 0.659574 (-3265 4960);
PAINT MONO (-3265 4960);
DISPLAY INVISIBLE (-3265 4960);
FORCEPROP 1 LASTPIN (-3275 4950) BN 19
J 0
(-3287 4958);
DISPLAY 0.489362 (-3287 4958);
PAINT GREEN (-3287 4958);
FORCEPROP 2 LAST CDS_LIB mstr_standard
J 0
(-3225 4950);
DISPLAY 0.723404 (-3225 4950);
PAINT MONO (-3225 4950);
DISPLAY INVISIBLE (-3225 4950);
FORCEPROP 1 LAST BODY_TYPE PLUMBING
J 0
(-3225 5000);
DISPLAY 0.872340 (-3225 5000);
PAINT GREEN (-3225 5000);
DISPLAY INVISIBLE (-3225 5000);
FORCEPROP 1 LAST HDL_TAP TRUE
J 0
(-2900 4825);
DISPLAY 0.872340 (-2900 4825);
DISPLAY INVISIBLE (-2900 4825);
FORCEPROP 1 LAST PATH I181
J 0
(-3227 4950);
DISPLAY 0.872340 (-3227 4950);
PAINT GREEN (-3227 4950);
DISPLAY INVISIBLE (-3227 4950);
FORCEADD TAP..1
(-3225 4900);
FORCEPROP 3 LASTPIN (-3275 4900) SIG_NAME M_L_CPU0_SA_DQ<20>
J 0
(-3265 4910);
DISPLAY 0.659574 (-3265 4910);
PAINT MONO (-3265 4910);
DISPLAY INVISIBLE (-3265 4910);
FORCEPROP 1 LASTPIN (-3275 4900) BN 20
J 0
(-3287 4908);
DISPLAY 0.489362 (-3287 4908);
PAINT GREEN (-3287 4908);
FORCEPROP 2 LAST CDS_LIB mstr_standard
J 0
(-3225 4900);
DISPLAY 0.723404 (-3225 4900);
PAINT MONO (-3225 4900);
DISPLAY INVISIBLE (-3225 4900);
FORCEPROP 1 LAST BODY_TYPE PLUMBING
J 0
(-3225 4950);
DISPLAY 0.872340 (-3225 4950);
PAINT GREEN (-3225 4950);
DISPLAY INVISIBLE (-3225 4950);
FORCEPROP 1 LAST HDL_TAP TRUE
J 0
(-2900 4775);
DISPLAY 0.872340 (-2900 4775);
DISPLAY INVISIBLE (-2900 4775);
FORCEPROP 1 LAST PATH I182
J 0
(-3227 4900);
DISPLAY 0.872340 (-3227 4900);
PAINT GREEN (-3227 4900);
DISPLAY INVISIBLE (-3227 4900);
FORCEADD TAP..1
(-3225 4800);
FORCEPROP 3 LASTPIN (-3275 4800) SIG_NAME M_L_CPU0_SA_DQ<22>
J 0
(-3265 4810);
DISPLAY 0.659574 (-3265 4810);
PAINT MONO (-3265 4810);
DISPLAY INVISIBLE (-3265 4810);
FORCEPROP 1 LASTPIN (-3275 4800) BN 22
J 0
(-3287 4808);
DISPLAY 0.489362 (-3287 4808);
PAINT GREEN (-3287 4808);
FORCEPROP 2 LAST CDS_LIB mstr_standard
J 0
(-3225 4800);
DISPLAY 0.723404 (-3225 4800);
PAINT MONO (-3225 4800);
DISPLAY INVISIBLE (-3225 4800);
FORCEPROP 1 LAST BODY_TYPE PLUMBING
J 0
(-3225 4850);
DISPLAY 0.872340 (-3225 4850);
PAINT GREEN (-3225 4850);
DISPLAY INVISIBLE (-3225 4850);
FORCEPROP 1 LAST HDL_TAP TRUE
J 0
(-2900 4675);
DISPLAY 0.872340 (-2900 4675);
DISPLAY INVISIBLE (-2900 4675);
FORCEPROP 1 LAST PATH I183
J 0
(-3227 4800);
DISPLAY 0.872340 (-3227 4800);
PAINT GREEN (-3227 4800);
DISPLAY INVISIBLE (-3227 4800);
FORCEADD TAP..1
(-3225 4850);
FORCEPROP 3 LASTPIN (-3275 4850) SIG_NAME M_L_CPU0_SA_DQ<21>
J 0
(-3265 4860);
DISPLAY 0.659574 (-3265 4860);
PAINT MONO (-3265 4860);
DISPLAY INVISIBLE (-3265 4860);
FORCEPROP 1 LASTPIN (-3275 4850) BN 21
J 0
(-3287 4858);
DISPLAY 0.489362 (-3287 4858);
PAINT GREEN (-3287 4858);
FORCEPROP 2 LAST CDS_LIB mstr_standard
J 0
(-3225 4850);
DISPLAY 0.723404 (-3225 4850);
PAINT MONO (-3225 4850);
DISPLAY INVISIBLE (-3225 4850);
FORCEPROP 1 LAST BODY_TYPE PLUMBING
J 0
(-3225 4900);
DISPLAY 0.872340 (-3225 4900);
PAINT GREEN (-3225 4900);
DISPLAY INVISIBLE (-3225 4900);
FORCEPROP 1 LAST HDL_TAP TRUE
J 0
(-2900 4725);
DISPLAY 0.872340 (-2900 4725);
DISPLAY INVISIBLE (-2900 4725);
FORCEPROP 1 LAST PATH I184
J 0
(-3227 4850);
DISPLAY 0.872340 (-3227 4850);
PAINT GREEN (-3227 4850);
DISPLAY INVISIBLE (-3227 4850);
FORCEADD TAP..1
(-3225 4750);
FORCEPROP 3 LASTPIN (-3275 4750) SIG_NAME M_L_CPU0_SA_DQ<23>
J 0
(-3265 4760);
DISPLAY 0.659574 (-3265 4760);
PAINT MONO (-3265 4760);
DISPLAY INVISIBLE (-3265 4760);
FORCEPROP 1 LASTPIN (-3275 4750) BN 23
J 0
(-3287 4758);
DISPLAY 0.489362 (-3287 4758);
PAINT GREEN (-3287 4758);
FORCEPROP 2 LAST CDS_LIB mstr_standard
J 0
(-3225 4750);
DISPLAY 0.723404 (-3225 4750);
PAINT MONO (-3225 4750);
DISPLAY INVISIBLE (-3225 4750);
FORCEPROP 1 LAST BODY_TYPE PLUMBING
J 0
(-3225 4800);
DISPLAY 0.872340 (-3225 4800);
PAINT GREEN (-3225 4800);
DISPLAY INVISIBLE (-3225 4800);
FORCEPROP 1 LAST HDL_TAP TRUE
J 0
(-2900 4625);
DISPLAY 0.872340 (-2900 4625);
DISPLAY INVISIBLE (-2900 4625);
FORCEPROP 1 LAST PATH I185
J 0
(-3227 4750);
DISPLAY 0.872340 (-3227 4750);
PAINT GREEN (-3227 4750);
DISPLAY INVISIBLE (-3227 4750);
FORCEADD TAP..1
(-3225 4650);
FORCEPROP 3 LASTPIN (-3275 4650) SIG_NAME M_L_CPU0_SA_DQ<24>
J 0
(-3265 4660);
DISPLAY 0.659574 (-3265 4660);
PAINT MONO (-3265 4660);
DISPLAY INVISIBLE (-3265 4660);
FORCEPROP 1 LASTPIN (-3275 4650) BN 24
J 0
(-3287 4658);
DISPLAY 0.489362 (-3287 4658);
PAINT GREEN (-3287 4658);
FORCEPROP 2 LAST CDS_LIB mstr_standard
J 0
(-3225 4650);
DISPLAY 0.723404 (-3225 4650);
PAINT MONO (-3225 4650);
DISPLAY INVISIBLE (-3225 4650);
FORCEPROP 1 LAST BODY_TYPE PLUMBING
J 0
(-3225 4700);
DISPLAY 0.872340 (-3225 4700);
PAINT GREEN (-3225 4700);
DISPLAY INVISIBLE (-3225 4700);
FORCEPROP 1 LAST HDL_TAP TRUE
J 0
(-2900 4525);
DISPLAY 0.872340 (-2900 4525);
DISPLAY INVISIBLE (-2900 4525);
FORCEPROP 1 LAST PATH I186
J 0
(-3227 4650);
DISPLAY 0.872340 (-3227 4650);
PAINT GREEN (-3227 4650);
DISPLAY INVISIBLE (-3227 4650);
FORCEADD TAP..1
(-3225 4550);
FORCEPROP 3 LASTPIN (-3275 4550) SIG_NAME M_L_CPU0_SA_DQ<26>
J 0
(-3265 4560);
DISPLAY 0.659574 (-3265 4560);
PAINT MONO (-3265 4560);
DISPLAY INVISIBLE (-3265 4560);
FORCEPROP 1 LASTPIN (-3275 4550) BN 26
J 0
(-3287 4558);
DISPLAY 0.489362 (-3287 4558);
PAINT GREEN (-3287 4558);
FORCEPROP 2 LAST CDS_LIB mstr_standard
J 0
(-3225 4550);
DISPLAY 0.723404 (-3225 4550);
PAINT MONO (-3225 4550);
DISPLAY INVISIBLE (-3225 4550);
FORCEPROP 1 LAST BODY_TYPE PLUMBING
J 0
(-3225 4600);
DISPLAY 0.872340 (-3225 4600);
PAINT GREEN (-3225 4600);
DISPLAY INVISIBLE (-3225 4600);
FORCEPROP 1 LAST HDL_TAP TRUE
J 0
(-2900 4425);
DISPLAY 0.872340 (-2900 4425);
DISPLAY INVISIBLE (-2900 4425);
FORCEPROP 1 LAST PATH I187
J 0
(-3227 4550);
DISPLAY 0.872340 (-3227 4550);
PAINT GREEN (-3227 4550);
DISPLAY INVISIBLE (-3227 4550);
FORCEADD TAP..1
(-3225 4600);
FORCEPROP 3 LASTPIN (-3275 4600) SIG_NAME M_L_CPU0_SA_DQ<25>
J 0
(-3265 4610);
DISPLAY 0.659574 (-3265 4610);
PAINT MONO (-3265 4610);
DISPLAY INVISIBLE (-3265 4610);
FORCEPROP 1 LASTPIN (-3275 4600) BN 25
J 0
(-3287 4608);
DISPLAY 0.489362 (-3287 4608);
PAINT GREEN (-3287 4608);
FORCEPROP 2 LAST CDS_LIB mstr_standard
J 0
(-3225 4600);
DISPLAY 0.723404 (-3225 4600);
PAINT MONO (-3225 4600);
DISPLAY INVISIBLE (-3225 4600);
FORCEPROP 1 LAST BODY_TYPE PLUMBING
J 0
(-3225 4650);
DISPLAY 0.872340 (-3225 4650);
PAINT GREEN (-3225 4650);
DISPLAY INVISIBLE (-3225 4650);
FORCEPROP 1 LAST HDL_TAP TRUE
J 0
(-2900 4475);
DISPLAY 0.872340 (-2900 4475);
DISPLAY INVISIBLE (-2900 4475);
FORCEPROP 1 LAST PATH I188
J 0
(-3227 4600);
DISPLAY 0.872340 (-3227 4600);
PAINT GREEN (-3227 4600);
DISPLAY INVISIBLE (-3227 4600);
FORCEADD TAP..1
(-3225 4500);
FORCEPROP 3 LASTPIN (-3275 4500) SIG_NAME M_L_CPU0_SA_DQ<27>
J 0
(-3265 4510);
DISPLAY 0.659574 (-3265 4510);
PAINT MONO (-3265 4510);
DISPLAY INVISIBLE (-3265 4510);
FORCEPROP 1 LASTPIN (-3275 4500) BN 27
J 0
(-3287 4508);
DISPLAY 0.489362 (-3287 4508);
PAINT GREEN (-3287 4508);
FORCEPROP 2 LAST CDS_LIB mstr_standard
J 0
(-3225 4500);
DISPLAY 0.723404 (-3225 4500);
PAINT MONO (-3225 4500);
DISPLAY INVISIBLE (-3225 4500);
FORCEPROP 1 LAST BODY_TYPE PLUMBING
J 0
(-3225 4550);
DISPLAY 0.872340 (-3225 4550);
PAINT GREEN (-3225 4550);
DISPLAY INVISIBLE (-3225 4550);
FORCEPROP 1 LAST HDL_TAP TRUE
J 0
(-2900 4375);
DISPLAY 0.872340 (-2900 4375);
DISPLAY INVISIBLE (-2900 4375);
FORCEPROP 1 LAST PATH I189
J 0
(-3227 4500);
DISPLAY 0.872340 (-3227 4500);
PAINT GREEN (-3227 4500);
DISPLAY INVISIBLE (-3227 4500);
FORCEADD TAP..1
(-3225 4450);
FORCEPROP 3 LASTPIN (-3275 4450) SIG_NAME M_L_CPU0_SA_DQ<28>
J 0
(-3265 4460);
DISPLAY 0.659574 (-3265 4460);
PAINT MONO (-3265 4460);
DISPLAY INVISIBLE (-3265 4460);
FORCEPROP 1 LASTPIN (-3275 4450) BN 28
J 0
(-3287 4458);
DISPLAY 0.489362 (-3287 4458);
PAINT GREEN (-3287 4458);
FORCEPROP 2 LAST CDS_LIB mstr_standard
J 0
(-3225 4450);
DISPLAY 0.723404 (-3225 4450);
PAINT MONO (-3225 4450);
DISPLAY INVISIBLE (-3225 4450);
FORCEPROP 1 LAST BODY_TYPE PLUMBING
J 0
(-3225 4500);
DISPLAY 0.872340 (-3225 4500);
PAINT GREEN (-3225 4500);
DISPLAY INVISIBLE (-3225 4500);
FORCEPROP 1 LAST HDL_TAP TRUE
J 0
(-2900 4325);
DISPLAY 0.872340 (-2900 4325);
DISPLAY INVISIBLE (-2900 4325);
FORCEPROP 1 LAST PATH I190
J 0
(-3227 4450);
DISPLAY 0.872340 (-3227 4450);
PAINT GREEN (-3227 4450);
DISPLAY INVISIBLE (-3227 4450);
FORCEADD TAP..1
(-3225 4400);
FORCEPROP 3 LASTPIN (-3275 4400) SIG_NAME M_L_CPU0_SA_DQ<29>
J 0
(-3265 4410);
DISPLAY 0.659574 (-3265 4410);
PAINT MONO (-3265 4410);
DISPLAY INVISIBLE (-3265 4410);
FORCEPROP 1 LASTPIN (-3275 4400) BN 29
J 0
(-3287 4408);
DISPLAY 0.489362 (-3287 4408);
PAINT GREEN (-3287 4408);
FORCEPROP 2 LAST CDS_LIB mstr_standard
J 0
(-3225 4400);
DISPLAY 0.723404 (-3225 4400);
PAINT MONO (-3225 4400);
DISPLAY INVISIBLE (-3225 4400);
FORCEPROP 1 LAST BODY_TYPE PLUMBING
J 0
(-3225 4450);
DISPLAY 0.872340 (-3225 4450);
PAINT GREEN (-3225 4450);
DISPLAY INVISIBLE (-3225 4450);
FORCEPROP 1 LAST HDL_TAP TRUE
J 0
(-2900 4275);
DISPLAY 0.872340 (-2900 4275);
DISPLAY INVISIBLE (-2900 4275);
FORCEPROP 1 LAST PATH I191
J 0
(-3227 4400);
DISPLAY 0.872340 (-3227 4400);
PAINT GREEN (-3227 4400);
DISPLAY INVISIBLE (-3227 4400);
FORCEADD TAP..1
(-3225 4300);
FORCEPROP 3 LASTPIN (-3275 4300) SIG_NAME M_L_CPU0_SA_DQ<31>
J 0
(-3265 4310);
DISPLAY 0.659574 (-3265 4310);
PAINT MONO (-3265 4310);
DISPLAY INVISIBLE (-3265 4310);
FORCEPROP 1 LASTPIN (-3275 4300) BN 31
J 0
(-3287 4308);
DISPLAY 0.489362 (-3287 4308);
PAINT GREEN (-3287 4308);
FORCEPROP 2 LAST CDS_LIB mstr_standard
J 0
(-3225 4300);
DISPLAY 0.723404 (-3225 4300);
PAINT MONO (-3225 4300);
DISPLAY INVISIBLE (-3225 4300);
FORCEPROP 1 LAST BODY_TYPE PLUMBING
J 0
(-3225 4350);
DISPLAY 0.872340 (-3225 4350);
PAINT GREEN (-3225 4350);
DISPLAY INVISIBLE (-3225 4350);
FORCEPROP 1 LAST HDL_TAP TRUE
J 0
(-2900 4175);
DISPLAY 0.872340 (-2900 4175);
DISPLAY INVISIBLE (-2900 4175);
FORCEPROP 1 LAST PATH I192
J 0
(-3227 4300);
DISPLAY 0.872340 (-3227 4300);
PAINT GREEN (-3227 4300);
DISPLAY INVISIBLE (-3227 4300);
FORCEADD TAP..1
(-3225 4350);
FORCEPROP 3 LASTPIN (-3275 4350) SIG_NAME M_L_CPU0_SA_DQ<30>
J 0
(-3265 4360);
DISPLAY 0.659574 (-3265 4360);
PAINT MONO (-3265 4360);
DISPLAY INVISIBLE (-3265 4360);
FORCEPROP 1 LASTPIN (-3275 4350) BN 30
J 0
(-3287 4358);
DISPLAY 0.489362 (-3287 4358);
PAINT GREEN (-3287 4358);
FORCEPROP 2 LAST CDS_LIB mstr_standard
J 0
(-3225 4350);
DISPLAY 0.723404 (-3225 4350);
PAINT MONO (-3225 4350);
DISPLAY INVISIBLE (-3225 4350);
FORCEPROP 1 LAST BODY_TYPE PLUMBING
J 0
(-3225 4400);
DISPLAY 0.872340 (-3225 4400);
PAINT GREEN (-3225 4400);
DISPLAY INVISIBLE (-3225 4400);
FORCEPROP 1 LAST HDL_TAP TRUE
J 0
(-2900 4225);
DISPLAY 0.872340 (-2900 4225);
DISPLAY INVISIBLE (-2900 4225);
FORCEPROP 1 LAST PATH I193
J 0
(-3227 4350);
DISPLAY 0.872340 (-3227 4350);
PAINT GREEN (-3227 4350);
DISPLAY INVISIBLE (-3227 4350);
FORCEADD TAP..1
(-3225 4150);
FORCEPROP 3 LASTPIN (-3275 4150) SIG_NAME M_L_CPU0_SB_DQ<1>
J 0
(-3265 4160);
DISPLAY 0.659574 (-3265 4160);
PAINT MONO (-3265 4160);
DISPLAY INVISIBLE (-3265 4160);
FORCEPROP 1 LASTPIN (-3275 4150) BN 1
J 0
(-3287 4158);
DISPLAY 0.489362 (-3287 4158);
PAINT GREEN (-3287 4158);
FORCEPROP 2 LAST CDS_LIB mstr_standard
J 0
(-3225 4150);
DISPLAY 0.723404 (-3225 4150);
PAINT MONO (-3225 4150);
DISPLAY INVISIBLE (-3225 4150);
FORCEPROP 1 LAST BODY_TYPE PLUMBING
J 0
(-3225 4200);
DISPLAY 0.872340 (-3225 4200);
PAINT GREEN (-3225 4200);
DISPLAY INVISIBLE (-3225 4200);
FORCEPROP 1 LAST HDL_TAP TRUE
J 0
(-2900 4025);
DISPLAY 0.872340 (-2900 4025);
DISPLAY INVISIBLE (-2900 4025);
FORCEPROP 1 LAST PATH I194
J 0
(-3227 4150);
DISPLAY 0.872340 (-3227 4150);
PAINT GREEN (-3227 4150);
DISPLAY INVISIBLE (-3227 4150);
FORCEADD TAP..1
(-3225 4200);
FORCEPROP 3 LASTPIN (-3275 4200) SIG_NAME M_L_CPU0_SB_DQ<0>
J 0
(-3265 4210);
DISPLAY 0.659574 (-3265 4210);
PAINT MONO (-3265 4210);
DISPLAY INVISIBLE (-3265 4210);
FORCEPROP 1 LASTPIN (-3275 4200) BN 0
J 0
(-3287 4208);
DISPLAY 0.489362 (-3287 4208);
PAINT GREEN (-3287 4208);
FORCEPROP 2 LAST CDS_LIB mstr_standard
J 0
(-3225 4200);
DISPLAY 0.723404 (-3225 4200);
PAINT MONO (-3225 4200);
DISPLAY INVISIBLE (-3225 4200);
FORCEPROP 1 LAST BODY_TYPE PLUMBING
J 0
(-3225 4250);
DISPLAY 0.872340 (-3225 4250);
PAINT GREEN (-3225 4250);
DISPLAY INVISIBLE (-3225 4250);
FORCEPROP 1 LAST HDL_TAP TRUE
J 0
(-2900 4075);
DISPLAY 0.872340 (-2900 4075);
DISPLAY INVISIBLE (-2900 4075);
FORCEPROP 1 LAST PATH I195
J 0
(-3227 4200);
DISPLAY 0.872340 (-3227 4200);
PAINT GREEN (-3227 4200);
DISPLAY INVISIBLE (-3227 4200);
FORCEADD TAP..1
(-3225 4100);
FORCEPROP 3 LASTPIN (-3275 4100) SIG_NAME M_L_CPU0_SB_DQ<2>
J 0
(-3265 4110);
DISPLAY 0.659574 (-3265 4110);
PAINT MONO (-3265 4110);
DISPLAY INVISIBLE (-3265 4110);
FORCEPROP 1 LASTPIN (-3275 4100) BN 2
J 0
(-3287 4108);
DISPLAY 0.489362 (-3287 4108);
PAINT GREEN (-3287 4108);
FORCEPROP 2 LAST CDS_LIB mstr_standard
J 0
(-3225 4100);
DISPLAY 0.723404 (-3225 4100);
PAINT MONO (-3225 4100);
DISPLAY INVISIBLE (-3225 4100);
FORCEPROP 1 LAST BODY_TYPE PLUMBING
J 0
(-3225 4150);
DISPLAY 0.872340 (-3225 4150);
PAINT GREEN (-3225 4150);
DISPLAY INVISIBLE (-3225 4150);
FORCEPROP 1 LAST HDL_TAP TRUE
J 0
(-2900 3975);
DISPLAY 0.872340 (-2900 3975);
DISPLAY INVISIBLE (-2900 3975);
FORCEPROP 1 LAST PATH I196
J 0
(-3227 4100);
DISPLAY 0.872340 (-3227 4100);
PAINT GREEN (-3227 4100);
DISPLAY INVISIBLE (-3227 4100);
FORCEADD OFFPAGE..6
R 2
(-2625 2450);
FORCEPROP 2 LAST $XR0 97 
J 0
(-2411 2450);
DISPLAY 0.638298 (-2411 2450);
PAINT MONO (-2411 2450);
FORCEPROP 2 LAST CDS_LIB mstr_standard
J 2
(-2625 2450);
DISPLAY 0.723404 (-2625 2450);
PAINT MONO (-2625 2450);
DISPLAY INVISIBLE (-2625 2450);
FORCEPROP 1 LAST OFFPAGE TRUE
J 2
(-2950 2325);
DISPLAY 0.872340 (-2950 2325);
PAINT GREEN (-2950 2325);
DISPLAY INVISIBLE (-2950 2325);
FORCEPROP 1 LAST COMMENT_BODY TRUE
J 2
(-2725 2375);
DISPLAY 0.872340 (-2725 2375);
PAINT GREEN (-2725 2375);
DISPLAY INVISIBLE (-2725 2375);
FORCEPROP 2 LAST PATH I197
J 0
(-2400 2500);
DISPLAY 1.021277 (-2400 2500);
DISPLAY INVISIBLE (-2400 2500);
FORCEADD TAP..1
(-3225 4050);
FORCEPROP 3 LASTPIN (-3275 4050) SIG_NAME M_L_CPU0_SB_DQ<3>
J 0
(-3265 4060);
DISPLAY 0.659574 (-3265 4060);
PAINT MONO (-3265 4060);
DISPLAY INVISIBLE (-3265 4060);
FORCEPROP 1 LASTPIN (-3275 4050) BN 3
J 0
(-3287 4058);
DISPLAY 0.489362 (-3287 4058);
PAINT GREEN (-3287 4058);
FORCEPROP 2 LAST CDS_LIB mstr_standard
J 0
(-3225 4050);
DISPLAY 0.723404 (-3225 4050);
PAINT MONO (-3225 4050);
DISPLAY INVISIBLE (-3225 4050);
FORCEPROP 1 LAST BODY_TYPE PLUMBING
J 0
(-3225 4100);
DISPLAY 0.872340 (-3225 4100);
PAINT GREEN (-3225 4100);
DISPLAY INVISIBLE (-3225 4100);
FORCEPROP 1 LAST HDL_TAP TRUE
J 0
(-2900 3925);
DISPLAY 0.872340 (-2900 3925);
DISPLAY INVISIBLE (-2900 3925);
FORCEPROP 1 LAST PATH I198
J 0
(-3227 4050);
DISPLAY 0.872340 (-3227 4050);
PAINT GREEN (-3227 4050);
DISPLAY INVISIBLE (-3227 4050);
FORCEADD TAP..1
(-3225 4000);
FORCEPROP 3 LASTPIN (-3275 4000) SIG_NAME M_L_CPU0_SB_DQ<4>
J 0
(-3265 4010);
DISPLAY 0.659574 (-3265 4010);
PAINT MONO (-3265 4010);
DISPLAY INVISIBLE (-3265 4010);
FORCEPROP 1 LASTPIN (-3275 4000) BN 4
J 0
(-3287 4008);
DISPLAY 0.489362 (-3287 4008);
PAINT GREEN (-3287 4008);
FORCEPROP 2 LAST CDS_LIB mstr_standard
J 0
(-3225 4000);
DISPLAY 0.723404 (-3225 4000);
PAINT MONO (-3225 4000);
DISPLAY INVISIBLE (-3225 4000);
FORCEPROP 1 LAST BODY_TYPE PLUMBING
J 0
(-3225 4050);
DISPLAY 0.872340 (-3225 4050);
PAINT GREEN (-3225 4050);
DISPLAY INVISIBLE (-3225 4050);
FORCEPROP 1 LAST HDL_TAP TRUE
J 0
(-2900 3875);
DISPLAY 0.872340 (-2900 3875);
DISPLAY INVISIBLE (-2900 3875);
FORCEPROP 1 LAST PATH I199
J 0
(-3227 4000);
DISPLAY 0.872340 (-3227 4000);
PAINT GREEN (-3227 4000);
DISPLAY INVISIBLE (-3227 4000);
FORCEADD TAP..1
(-3225 3950);
FORCEPROP 3 LASTPIN (-3275 3950) SIG_NAME M_L_CPU0_SB_DQ<5>
J 0
(-3265 3960);
DISPLAY 0.659574 (-3265 3960);
PAINT MONO (-3265 3960);
DISPLAY INVISIBLE (-3265 3960);
FORCEPROP 1 LASTPIN (-3275 3950) BN 5
J 0
(-3287 3958);
DISPLAY 0.489362 (-3287 3958);
PAINT GREEN (-3287 3958);
FORCEPROP 2 LAST CDS_LIB mstr_standard
J 0
(-3225 3950);
DISPLAY 0.723404 (-3225 3950);
PAINT MONO (-3225 3950);
DISPLAY INVISIBLE (-3225 3950);
FORCEPROP 1 LAST BODY_TYPE PLUMBING
J 0
(-3225 4000);
DISPLAY 0.872340 (-3225 4000);
PAINT GREEN (-3225 4000);
DISPLAY INVISIBLE (-3225 4000);
FORCEPROP 1 LAST HDL_TAP TRUE
J 0
(-2900 3825);
DISPLAY 0.872340 (-2900 3825);
DISPLAY INVISIBLE (-2900 3825);
FORCEPROP 1 LAST PATH I200
J 0
(-3227 3950);
DISPLAY 0.872340 (-3227 3950);
PAINT GREEN (-3227 3950);
DISPLAY INVISIBLE (-3227 3950);
FORCEADD TAP..1
(-3225 3900);
FORCEPROP 3 LASTPIN (-3275 3900) SIG_NAME M_L_CPU0_SB_DQ<6>
J 0
(-3265 3910);
DISPLAY 0.659574 (-3265 3910);
PAINT MONO (-3265 3910);
DISPLAY INVISIBLE (-3265 3910);
FORCEPROP 1 LASTPIN (-3275 3900) BN 6
J 0
(-3287 3908);
DISPLAY 0.489362 (-3287 3908);
PAINT GREEN (-3287 3908);
FORCEPROP 2 LAST CDS_LIB mstr_standard
J 0
(-3225 3900);
DISPLAY 0.723404 (-3225 3900);
PAINT MONO (-3225 3900);
DISPLAY INVISIBLE (-3225 3900);
FORCEPROP 1 LAST BODY_TYPE PLUMBING
J 0
(-3225 3950);
DISPLAY 0.872340 (-3225 3950);
PAINT GREEN (-3225 3950);
DISPLAY INVISIBLE (-3225 3950);
FORCEPROP 1 LAST HDL_TAP TRUE
J 0
(-2900 3775);
DISPLAY 0.872340 (-2900 3775);
DISPLAY INVISIBLE (-2900 3775);
FORCEPROP 1 LAST PATH I201
J 0
(-3227 3900);
DISPLAY 0.872340 (-3227 3900);
PAINT GREEN (-3227 3900);
DISPLAY INVISIBLE (-3227 3900);
FORCEADD TAP..1
(-3225 3850);
FORCEPROP 3 LASTPIN (-3275 3850) SIG_NAME M_L_CPU0_SB_DQ<7>
J 0
(-3265 3860);
DISPLAY 0.659574 (-3265 3860);
PAINT MONO (-3265 3860);
DISPLAY INVISIBLE (-3265 3860);
FORCEPROP 1 LASTPIN (-3275 3850) BN 7
J 0
(-3287 3858);
DISPLAY 0.489362 (-3287 3858);
PAINT GREEN (-3287 3858);
FORCEPROP 2 LAST CDS_LIB mstr_standard
J 0
(-3225 3850);
DISPLAY 0.723404 (-3225 3850);
PAINT MONO (-3225 3850);
DISPLAY INVISIBLE (-3225 3850);
FORCEPROP 1 LAST BODY_TYPE PLUMBING
J 0
(-3225 3900);
DISPLAY 0.872340 (-3225 3900);
PAINT GREEN (-3225 3900);
DISPLAY INVISIBLE (-3225 3900);
FORCEPROP 1 LAST HDL_TAP TRUE
J 0
(-2900 3725);
DISPLAY 0.872340 (-2900 3725);
DISPLAY INVISIBLE (-2900 3725);
FORCEPROP 1 LAST PATH I202
J 0
(-3227 3850);
DISPLAY 0.872340 (-3227 3850);
PAINT GREEN (-3227 3850);
DISPLAY INVISIBLE (-3227 3850);
FORCEADD TAP..1
(-3225 3650);
FORCEPROP 3 LASTPIN (-3275 3650) SIG_NAME M_L_CPU0_SB_DQ<10>
J 0
(-3265 3660);
DISPLAY 0.659574 (-3265 3660);
PAINT MONO (-3265 3660);
DISPLAY INVISIBLE (-3265 3660);
FORCEPROP 1 LASTPIN (-3275 3650) BN 10
J 0
(-3287 3658);
DISPLAY 0.489362 (-3287 3658);
PAINT GREEN (-3287 3658);
FORCEPROP 2 LAST CDS_LIB mstr_standard
J 0
(-3225 3650);
DISPLAY 0.723404 (-3225 3650);
PAINT MONO (-3225 3650);
DISPLAY INVISIBLE (-3225 3650);
FORCEPROP 1 LAST BODY_TYPE PLUMBING
J 0
(-3225 3700);
DISPLAY 0.872340 (-3225 3700);
PAINT GREEN (-3225 3700);
DISPLAY INVISIBLE (-3225 3700);
FORCEPROP 1 LAST HDL_TAP TRUE
J 0
(-2900 3525);
DISPLAY 0.872340 (-2900 3525);
DISPLAY INVISIBLE (-2900 3525);
FORCEPROP 1 LAST PATH I203
J 0
(-3227 3650);
DISPLAY 0.872340 (-3227 3650);
PAINT GREEN (-3227 3650);
DISPLAY INVISIBLE (-3227 3650);
FORCEADD TAP..1
(-3225 3700);
FORCEPROP 3 LASTPIN (-3275 3700) SIG_NAME M_L_CPU0_SB_DQ<9>
J 0
(-3265 3710);
DISPLAY 0.659574 (-3265 3710);
PAINT MONO (-3265 3710);
DISPLAY INVISIBLE (-3265 3710);
FORCEPROP 1 LASTPIN (-3275 3700) BN 9
J 0
(-3287 3708);
DISPLAY 0.489362 (-3287 3708);
PAINT GREEN (-3287 3708);
FORCEPROP 2 LAST CDS_LIB mstr_standard
J 0
(-3225 3700);
DISPLAY 0.723404 (-3225 3700);
PAINT MONO (-3225 3700);
DISPLAY INVISIBLE (-3225 3700);
FORCEPROP 1 LAST BODY_TYPE PLUMBING
J 0
(-3225 3750);
DISPLAY 0.872340 (-3225 3750);
PAINT GREEN (-3225 3750);
DISPLAY INVISIBLE (-3225 3750);
FORCEPROP 1 LAST HDL_TAP TRUE
J 0
(-2900 3575);
DISPLAY 0.872340 (-2900 3575);
DISPLAY INVISIBLE (-2900 3575);
FORCEPROP 1 LAST PATH I204
J 0
(-3227 3700);
DISPLAY 0.872340 (-3227 3700);
PAINT GREEN (-3227 3700);
DISPLAY INVISIBLE (-3227 3700);
FORCEADD TAP..1
(-3225 3750);
FORCEPROP 3 LASTPIN (-3275 3750) SIG_NAME M_L_CPU0_SB_DQ<8>
J 0
(-3265 3760);
DISPLAY 0.659574 (-3265 3760);
PAINT MONO (-3265 3760);
DISPLAY INVISIBLE (-3265 3760);
FORCEPROP 1 LASTPIN (-3275 3750) BN 8
J 0
(-3287 3758);
DISPLAY 0.489362 (-3287 3758);
PAINT GREEN (-3287 3758);
FORCEPROP 2 LAST CDS_LIB mstr_standard
J 0
(-3225 3750);
DISPLAY 0.723404 (-3225 3750);
PAINT MONO (-3225 3750);
DISPLAY INVISIBLE (-3225 3750);
FORCEPROP 1 LAST BODY_TYPE PLUMBING
J 0
(-3225 3800);
DISPLAY 0.872340 (-3225 3800);
PAINT GREEN (-3225 3800);
DISPLAY INVISIBLE (-3225 3800);
FORCEPROP 1 LAST HDL_TAP TRUE
J 0
(-2900 3625);
DISPLAY 0.872340 (-2900 3625);
DISPLAY INVISIBLE (-2900 3625);
FORCEPROP 1 LAST PATH I205
J 0
(-3227 3750);
DISPLAY 0.872340 (-3227 3750);
PAINT GREEN (-3227 3750);
DISPLAY INVISIBLE (-3227 3750);
FORCEADD TAP..1
(-3225 3600);
FORCEPROP 3 LASTPIN (-3275 3600) SIG_NAME M_L_CPU0_SB_DQ<11>
J 0
(-3265 3610);
DISPLAY 0.659574 (-3265 3610);
PAINT MONO (-3265 3610);
DISPLAY INVISIBLE (-3265 3610);
FORCEPROP 1 LASTPIN (-3275 3600) BN 11
J 0
(-3287 3608);
DISPLAY 0.489362 (-3287 3608);
PAINT GREEN (-3287 3608);
FORCEPROP 2 LAST CDS_LIB mstr_standard
J 0
(-3225 3600);
DISPLAY 0.723404 (-3225 3600);
PAINT MONO (-3225 3600);
DISPLAY INVISIBLE (-3225 3600);
FORCEPROP 1 LAST BODY_TYPE PLUMBING
J 0
(-3225 3650);
DISPLAY 0.872340 (-3225 3650);
PAINT GREEN (-3225 3650);
DISPLAY INVISIBLE (-3225 3650);
FORCEPROP 1 LAST HDL_TAP TRUE
J 0
(-2900 3475);
DISPLAY 0.872340 (-2900 3475);
DISPLAY INVISIBLE (-2900 3475);
FORCEPROP 1 LAST PATH I206
J 0
(-3227 3600);
DISPLAY 0.872340 (-3227 3600);
PAINT GREEN (-3227 3600);
DISPLAY INVISIBLE (-3227 3600);
FORCEADD TAP..1
(-3225 3550);
FORCEPROP 3 LASTPIN (-3275 3550) SIG_NAME M_L_CPU0_SB_DQ<12>
J 0
(-3265 3560);
DISPLAY 0.659574 (-3265 3560);
PAINT MONO (-3265 3560);
DISPLAY INVISIBLE (-3265 3560);
FORCEPROP 1 LASTPIN (-3275 3550) BN 12
J 0
(-3287 3558);
DISPLAY 0.489362 (-3287 3558);
PAINT GREEN (-3287 3558);
FORCEPROP 2 LAST CDS_LIB mstr_standard
J 0
(-3225 3550);
DISPLAY 0.723404 (-3225 3550);
PAINT MONO (-3225 3550);
DISPLAY INVISIBLE (-3225 3550);
FORCEPROP 1 LAST BODY_TYPE PLUMBING
J 0
(-3225 3600);
DISPLAY 0.872340 (-3225 3600);
PAINT GREEN (-3225 3600);
DISPLAY INVISIBLE (-3225 3600);
FORCEPROP 1 LAST HDL_TAP TRUE
J 0
(-2900 3425);
DISPLAY 0.872340 (-2900 3425);
DISPLAY INVISIBLE (-2900 3425);
FORCEPROP 1 LAST PATH I207
J 0
(-3227 3550);
DISPLAY 0.872340 (-3227 3550);
PAINT GREEN (-3227 3550);
DISPLAY INVISIBLE (-3227 3550);
FORCEADD TAP..1
(-3225 3450);
FORCEPROP 3 LASTPIN (-3275 3450) SIG_NAME M_L_CPU0_SB_DQ<14>
J 0
(-3265 3460);
DISPLAY 0.659574 (-3265 3460);
PAINT MONO (-3265 3460);
DISPLAY INVISIBLE (-3265 3460);
FORCEPROP 1 LASTPIN (-3275 3450) BN 14
J 0
(-3287 3458);
DISPLAY 0.489362 (-3287 3458);
PAINT GREEN (-3287 3458);
FORCEPROP 2 LAST CDS_LIB mstr_standard
J 0
(-3225 3450);
DISPLAY 0.723404 (-3225 3450);
PAINT MONO (-3225 3450);
DISPLAY INVISIBLE (-3225 3450);
FORCEPROP 1 LAST BODY_TYPE PLUMBING
J 0
(-3225 3500);
DISPLAY 0.872340 (-3225 3500);
PAINT GREEN (-3225 3500);
DISPLAY INVISIBLE (-3225 3500);
FORCEPROP 1 LAST HDL_TAP TRUE
J 0
(-2900 3325);
DISPLAY 0.872340 (-2900 3325);
DISPLAY INVISIBLE (-2900 3325);
FORCEPROP 1 LAST PATH I208
J 0
(-3227 3450);
DISPLAY 0.872340 (-3227 3450);
PAINT GREEN (-3227 3450);
DISPLAY INVISIBLE (-3227 3450);
FORCEADD TAP..1
(-3225 3400);
FORCEPROP 3 LASTPIN (-3275 3400) SIG_NAME M_L_CPU0_SB_DQ<15>
J 0
(-3265 3410);
DISPLAY 0.659574 (-3265 3410);
PAINT MONO (-3265 3410);
DISPLAY INVISIBLE (-3265 3410);
FORCEPROP 1 LASTPIN (-3275 3400) BN 15
J 0
(-3287 3408);
DISPLAY 0.489362 (-3287 3408);
PAINT GREEN (-3287 3408);
FORCEPROP 2 LAST CDS_LIB mstr_standard
J 0
(-3225 3400);
DISPLAY 0.723404 (-3225 3400);
PAINT MONO (-3225 3400);
DISPLAY INVISIBLE (-3225 3400);
FORCEPROP 1 LAST BODY_TYPE PLUMBING
J 0
(-3225 3450);
DISPLAY 0.872340 (-3225 3450);
PAINT GREEN (-3225 3450);
DISPLAY INVISIBLE (-3225 3450);
FORCEPROP 1 LAST HDL_TAP TRUE
J 0
(-2900 3275);
DISPLAY 0.872340 (-2900 3275);
DISPLAY INVISIBLE (-2900 3275);
FORCEPROP 1 LAST PATH I209
J 0
(-3227 3400);
DISPLAY 0.872340 (-3227 3400);
PAINT GREEN (-3227 3400);
DISPLAY INVISIBLE (-3227 3400);
FORCEADD TAP..1
(-3225 3500);
FORCEPROP 3 LASTPIN (-3275 3500) SIG_NAME M_L_CPU0_SB_DQ<13>
J 0
(-3265 3510);
DISPLAY 0.659574 (-3265 3510);
PAINT MONO (-3265 3510);
DISPLAY INVISIBLE (-3265 3510);
FORCEPROP 1 LASTPIN (-3275 3500) BN 13
J 0
(-3287 3508);
DISPLAY 0.489362 (-3287 3508);
PAINT GREEN (-3287 3508);
FORCEPROP 2 LAST CDS_LIB mstr_standard
J 0
(-3225 3500);
DISPLAY 0.723404 (-3225 3500);
PAINT MONO (-3225 3500);
DISPLAY INVISIBLE (-3225 3500);
FORCEPROP 1 LAST BODY_TYPE PLUMBING
J 0
(-3225 3550);
DISPLAY 0.872340 (-3225 3550);
PAINT GREEN (-3225 3550);
DISPLAY INVISIBLE (-3225 3550);
FORCEPROP 1 LAST HDL_TAP TRUE
J 0
(-2900 3375);
DISPLAY 0.872340 (-2900 3375);
DISPLAY INVISIBLE (-2900 3375);
FORCEPROP 1 LAST PATH I210
J 0
(-3227 3500);
DISPLAY 0.872340 (-3227 3500);
PAINT GREEN (-3227 3500);
DISPLAY INVISIBLE (-3227 3500);
FORCEADD TAP..1
(-3225 3300);
FORCEPROP 3 LASTPIN (-3275 3300) SIG_NAME M_L_CPU0_SB_DQ<16>
J 0
(-3265 3310);
DISPLAY 0.659574 (-3265 3310);
PAINT MONO (-3265 3310);
DISPLAY INVISIBLE (-3265 3310);
FORCEPROP 1 LASTPIN (-3275 3300) BN 16
J 0
(-3287 3308);
DISPLAY 0.489362 (-3287 3308);
PAINT GREEN (-3287 3308);
FORCEPROP 2 LAST CDS_LIB mstr_standard
J 0
(-3225 3300);
DISPLAY 0.723404 (-3225 3300);
PAINT MONO (-3225 3300);
DISPLAY INVISIBLE (-3225 3300);
FORCEPROP 1 LAST BODY_TYPE PLUMBING
J 0
(-3225 3350);
DISPLAY 0.872340 (-3225 3350);
PAINT GREEN (-3225 3350);
DISPLAY INVISIBLE (-3225 3350);
FORCEPROP 1 LAST HDL_TAP TRUE
J 0
(-2900 3175);
DISPLAY 0.872340 (-2900 3175);
DISPLAY INVISIBLE (-2900 3175);
FORCEPROP 1 LAST PATH I211
J 0
(-3227 3300);
DISPLAY 0.872340 (-3227 3300);
PAINT GREEN (-3227 3300);
DISPLAY INVISIBLE (-3227 3300);
FORCEADD TAP..1
(-3225 3250);
FORCEPROP 3 LASTPIN (-3275 3250) SIG_NAME M_L_CPU0_SB_DQ<17>
J 0
(-3265 3260);
DISPLAY 0.659574 (-3265 3260);
PAINT MONO (-3265 3260);
DISPLAY INVISIBLE (-3265 3260);
FORCEPROP 1 LASTPIN (-3275 3250) BN 17
J 0
(-3287 3258);
DISPLAY 0.489362 (-3287 3258);
PAINT GREEN (-3287 3258);
FORCEPROP 2 LAST CDS_LIB mstr_standard
J 0
(-3225 3250);
DISPLAY 0.723404 (-3225 3250);
PAINT MONO (-3225 3250);
DISPLAY INVISIBLE (-3225 3250);
FORCEPROP 1 LAST BODY_TYPE PLUMBING
J 0
(-3225 3300);
DISPLAY 0.872340 (-3225 3300);
PAINT GREEN (-3225 3300);
DISPLAY INVISIBLE (-3225 3300);
FORCEPROP 1 LAST HDL_TAP TRUE
J 0
(-2900 3125);
DISPLAY 0.872340 (-2900 3125);
DISPLAY INVISIBLE (-2900 3125);
FORCEPROP 1 LAST PATH I212
J 0
(-3227 3250);
DISPLAY 0.872340 (-3227 3250);
PAINT GREEN (-3227 3250);
DISPLAY INVISIBLE (-3227 3250);
FORCEADD TAP..1
(-3225 3200);
FORCEPROP 3 LASTPIN (-3275 3200) SIG_NAME M_L_CPU0_SB_DQ<18>
J 0
(-3265 3210);
DISPLAY 0.659574 (-3265 3210);
PAINT MONO (-3265 3210);
DISPLAY INVISIBLE (-3265 3210);
FORCEPROP 1 LASTPIN (-3275 3200) BN 18
J 0
(-3287 3208);
DISPLAY 0.489362 (-3287 3208);
PAINT GREEN (-3287 3208);
FORCEPROP 2 LAST CDS_LIB mstr_standard
J 0
(-3225 3200);
DISPLAY 0.723404 (-3225 3200);
PAINT MONO (-3225 3200);
DISPLAY INVISIBLE (-3225 3200);
FORCEPROP 1 LAST BODY_TYPE PLUMBING
J 0
(-3225 3250);
DISPLAY 0.872340 (-3225 3250);
PAINT GREEN (-3225 3250);
DISPLAY INVISIBLE (-3225 3250);
FORCEPROP 1 LAST HDL_TAP TRUE
J 0
(-2900 3075);
DISPLAY 0.872340 (-2900 3075);
DISPLAY INVISIBLE (-2900 3075);
FORCEPROP 1 LAST PATH I213
J 0
(-3227 3200);
DISPLAY 0.872340 (-3227 3200);
PAINT GREEN (-3227 3200);
DISPLAY INVISIBLE (-3227 3200);
FORCEADD TAP..1
(-3225 3150);
FORCEPROP 3 LASTPIN (-3275 3150) SIG_NAME M_L_CPU0_SB_DQ<19>
J 0
(-3265 3160);
DISPLAY 0.659574 (-3265 3160);
PAINT MONO (-3265 3160);
DISPLAY INVISIBLE (-3265 3160);
FORCEPROP 1 LASTPIN (-3275 3150) BN 19
J 0
(-3287 3158);
DISPLAY 0.489362 (-3287 3158);
PAINT GREEN (-3287 3158);
FORCEPROP 2 LAST CDS_LIB mstr_standard
J 0
(-3225 3150);
DISPLAY 0.723404 (-3225 3150);
PAINT MONO (-3225 3150);
DISPLAY INVISIBLE (-3225 3150);
FORCEPROP 1 LAST BODY_TYPE PLUMBING
J 0
(-3225 3200);
DISPLAY 0.872340 (-3225 3200);
PAINT GREEN (-3225 3200);
DISPLAY INVISIBLE (-3225 3200);
FORCEPROP 1 LAST HDL_TAP TRUE
J 0
(-2900 3025);
DISPLAY 0.872340 (-2900 3025);
DISPLAY INVISIBLE (-2900 3025);
FORCEPROP 1 LAST PATH I214
J 0
(-3227 3150);
DISPLAY 0.872340 (-3227 3150);
PAINT GREEN (-3227 3150);
DISPLAY INVISIBLE (-3227 3150);
FORCEADD TAP..1
(-3225 3100);
FORCEPROP 3 LASTPIN (-3275 3100) SIG_NAME M_L_CPU0_SB_DQ<20>
J 0
(-3265 3110);
DISPLAY 0.659574 (-3265 3110);
PAINT MONO (-3265 3110);
DISPLAY INVISIBLE (-3265 3110);
FORCEPROP 1 LASTPIN (-3275 3100) BN 20
J 0
(-3287 3108);
DISPLAY 0.489362 (-3287 3108);
PAINT GREEN (-3287 3108);
FORCEPROP 2 LAST CDS_LIB mstr_standard
J 0
(-3225 3100);
DISPLAY 0.723404 (-3225 3100);
PAINT MONO (-3225 3100);
DISPLAY INVISIBLE (-3225 3100);
FORCEPROP 1 LAST BODY_TYPE PLUMBING
J 0
(-3225 3150);
DISPLAY 0.872340 (-3225 3150);
PAINT GREEN (-3225 3150);
DISPLAY INVISIBLE (-3225 3150);
FORCEPROP 1 LAST HDL_TAP TRUE
J 0
(-2900 2975);
DISPLAY 0.872340 (-2900 2975);
DISPLAY INVISIBLE (-2900 2975);
FORCEPROP 1 LAST PATH I215
J 0
(-3227 3100);
DISPLAY 0.872340 (-3227 3100);
PAINT GREEN (-3227 3100);
DISPLAY INVISIBLE (-3227 3100);
FORCEADD TAP..1
(-3225 2850);
FORCEPROP 3 LASTPIN (-3275 2850) SIG_NAME M_L_CPU0_SB_DQ<24>
J 0
(-3265 2860);
DISPLAY 0.659574 (-3265 2860);
PAINT MONO (-3265 2860);
DISPLAY INVISIBLE (-3265 2860);
FORCEPROP 1 LASTPIN (-3275 2850) BN 24
J 0
(-3287 2858);
DISPLAY 0.489362 (-3287 2858);
PAINT GREEN (-3287 2858);
FORCEPROP 2 LAST CDS_LIB mstr_standard
J 0
(-3225 2850);
DISPLAY 0.723404 (-3225 2850);
PAINT MONO (-3225 2850);
DISPLAY INVISIBLE (-3225 2850);
FORCEPROP 1 LAST BODY_TYPE PLUMBING
J 0
(-3225 2900);
DISPLAY 0.872340 (-3225 2900);
PAINT GREEN (-3225 2900);
DISPLAY INVISIBLE (-3225 2900);
FORCEPROP 1 LAST HDL_TAP TRUE
J 0
(-2900 2725);
DISPLAY 0.872340 (-2900 2725);
DISPLAY INVISIBLE (-2900 2725);
FORCEPROP 1 LAST PATH I216
J 0
(-3227 2850);
DISPLAY 0.872340 (-3227 2850);
PAINT GREEN (-3227 2850);
DISPLAY INVISIBLE (-3227 2850);
FORCEADD TAP..1
(-3225 3050);
FORCEPROP 3 LASTPIN (-3275 3050) SIG_NAME M_L_CPU0_SB_DQ<21>
J 0
(-3265 3060);
DISPLAY 0.659574 (-3265 3060);
PAINT MONO (-3265 3060);
DISPLAY INVISIBLE (-3265 3060);
FORCEPROP 1 LASTPIN (-3275 3050) BN 21
J 0
(-3287 3058);
DISPLAY 0.489362 (-3287 3058);
PAINT GREEN (-3287 3058);
FORCEPROP 2 LAST CDS_LIB mstr_standard
J 0
(-3225 3050);
DISPLAY 0.723404 (-3225 3050);
PAINT MONO (-3225 3050);
DISPLAY INVISIBLE (-3225 3050);
FORCEPROP 1 LAST BODY_TYPE PLUMBING
J 0
(-3225 3100);
DISPLAY 0.872340 (-3225 3100);
PAINT GREEN (-3225 3100);
DISPLAY INVISIBLE (-3225 3100);
FORCEPROP 1 LAST HDL_TAP TRUE
J 0
(-2900 2925);
DISPLAY 0.872340 (-2900 2925);
DISPLAY INVISIBLE (-2900 2925);
FORCEPROP 1 LAST PATH I217
J 0
(-3227 3050);
DISPLAY 0.872340 (-3227 3050);
PAINT GREEN (-3227 3050);
DISPLAY INVISIBLE (-3227 3050);
FORCEADD TAP..1
(-3225 3000);
FORCEPROP 3 LASTPIN (-3275 3000) SIG_NAME M_L_CPU0_SB_DQ<22>
J 0
(-3265 3010);
DISPLAY 0.659574 (-3265 3010);
PAINT MONO (-3265 3010);
DISPLAY INVISIBLE (-3265 3010);
FORCEPROP 1 LASTPIN (-3275 3000) BN 22
J 0
(-3287 3008);
DISPLAY 0.489362 (-3287 3008);
PAINT GREEN (-3287 3008);
FORCEPROP 2 LAST CDS_LIB mstr_standard
J 0
(-3225 3000);
DISPLAY 0.723404 (-3225 3000);
PAINT MONO (-3225 3000);
DISPLAY INVISIBLE (-3225 3000);
FORCEPROP 1 LAST BODY_TYPE PLUMBING
J 0
(-3225 3050);
DISPLAY 0.872340 (-3225 3050);
PAINT GREEN (-3225 3050);
DISPLAY INVISIBLE (-3225 3050);
FORCEPROP 1 LAST HDL_TAP TRUE
J 0
(-2900 2875);
DISPLAY 0.872340 (-2900 2875);
DISPLAY INVISIBLE (-2900 2875);
FORCEPROP 1 LAST PATH I218
J 0
(-3227 3000);
DISPLAY 0.872340 (-3227 3000);
PAINT GREEN (-3227 3000);
DISPLAY INVISIBLE (-3227 3000);
FORCEADD TAP..1
(-3225 2950);
FORCEPROP 3 LASTPIN (-3275 2950) SIG_NAME M_L_CPU0_SB_DQ<23>
J 0
(-3265 2960);
DISPLAY 0.659574 (-3265 2960);
PAINT MONO (-3265 2960);
DISPLAY INVISIBLE (-3265 2960);
FORCEPROP 1 LASTPIN (-3275 2950) BN 23
J 0
(-3287 2958);
DISPLAY 0.489362 (-3287 2958);
PAINT GREEN (-3287 2958);
FORCEPROP 2 LAST CDS_LIB mstr_standard
J 0
(-3225 2950);
DISPLAY 0.723404 (-3225 2950);
PAINT MONO (-3225 2950);
DISPLAY INVISIBLE (-3225 2950);
FORCEPROP 1 LAST BODY_TYPE PLUMBING
J 0
(-3225 3000);
DISPLAY 0.872340 (-3225 3000);
PAINT GREEN (-3225 3000);
DISPLAY INVISIBLE (-3225 3000);
FORCEPROP 1 LAST HDL_TAP TRUE
J 0
(-2900 2825);
DISPLAY 0.872340 (-2900 2825);
DISPLAY INVISIBLE (-2900 2825);
FORCEPROP 1 LAST PATH I219
J 0
(-3227 2950);
DISPLAY 0.872340 (-3227 2950);
PAINT GREEN (-3227 2950);
DISPLAY INVISIBLE (-3227 2950);
FORCEADD TAP..1
(-3225 2800);
FORCEPROP 3 LASTPIN (-3275 2800) SIG_NAME M_L_CPU0_SB_DQ<25>
J 0
(-3265 2810);
DISPLAY 0.659574 (-3265 2810);
PAINT MONO (-3265 2810);
DISPLAY INVISIBLE (-3265 2810);
FORCEPROP 1 LASTPIN (-3275 2800) BN 25
J 0
(-3287 2808);
DISPLAY 0.489362 (-3287 2808);
PAINT GREEN (-3287 2808);
FORCEPROP 2 LAST CDS_LIB mstr_standard
J 0
(-3225 2800);
DISPLAY 0.723404 (-3225 2800);
PAINT MONO (-3225 2800);
DISPLAY INVISIBLE (-3225 2800);
FORCEPROP 1 LAST BODY_TYPE PLUMBING
J 0
(-3225 2850);
DISPLAY 0.872340 (-3225 2850);
PAINT GREEN (-3225 2850);
DISPLAY INVISIBLE (-3225 2850);
FORCEPROP 1 LAST HDL_TAP TRUE
J 0
(-2900 2675);
DISPLAY 0.872340 (-2900 2675);
DISPLAY INVISIBLE (-2900 2675);
FORCEPROP 1 LAST PATH I220
J 0
(-3227 2800);
DISPLAY 0.872340 (-3227 2800);
PAINT GREEN (-3227 2800);
DISPLAY INVISIBLE (-3227 2800);
FORCEADD TAP..1
(-3225 2750);
FORCEPROP 3 LASTPIN (-3275 2750) SIG_NAME M_L_CPU0_SB_DQ<26>
J 0
(-3265 2760);
DISPLAY 0.659574 (-3265 2760);
PAINT MONO (-3265 2760);
DISPLAY INVISIBLE (-3265 2760);
FORCEPROP 1 LASTPIN (-3275 2750) BN 26
J 0
(-3287 2758);
DISPLAY 0.489362 (-3287 2758);
PAINT GREEN (-3287 2758);
FORCEPROP 2 LAST CDS_LIB mstr_standard
J 0
(-3225 2750);
DISPLAY 0.723404 (-3225 2750);
PAINT MONO (-3225 2750);
DISPLAY INVISIBLE (-3225 2750);
FORCEPROP 1 LAST BODY_TYPE PLUMBING
J 0
(-3225 2800);
DISPLAY 0.872340 (-3225 2800);
PAINT GREEN (-3225 2800);
DISPLAY INVISIBLE (-3225 2800);
FORCEPROP 1 LAST HDL_TAP TRUE
J 0
(-2900 2625);
DISPLAY 0.872340 (-2900 2625);
DISPLAY INVISIBLE (-2900 2625);
FORCEPROP 1 LAST PATH I221
J 0
(-3227 2750);
DISPLAY 0.872340 (-3227 2750);
PAINT GREEN (-3227 2750);
DISPLAY INVISIBLE (-3227 2750);
FORCEADD TAP..1
(-3225 2700);
FORCEPROP 3 LASTPIN (-3275 2700) SIG_NAME M_L_CPU0_SB_DQ<27>
J 0
(-3265 2710);
DISPLAY 0.659574 (-3265 2710);
PAINT MONO (-3265 2710);
DISPLAY INVISIBLE (-3265 2710);
FORCEPROP 1 LASTPIN (-3275 2700) BN 27
J 0
(-3287 2708);
DISPLAY 0.489362 (-3287 2708);
PAINT GREEN (-3287 2708);
FORCEPROP 2 LAST CDS_LIB mstr_standard
J 0
(-3225 2700);
DISPLAY 0.723404 (-3225 2700);
PAINT MONO (-3225 2700);
DISPLAY INVISIBLE (-3225 2700);
FORCEPROP 1 LAST BODY_TYPE PLUMBING
J 0
(-3225 2750);
DISPLAY 0.872340 (-3225 2750);
PAINT GREEN (-3225 2750);
DISPLAY INVISIBLE (-3225 2750);
FORCEPROP 1 LAST HDL_TAP TRUE
J 0
(-2900 2575);
DISPLAY 0.872340 (-2900 2575);
DISPLAY INVISIBLE (-2900 2575);
FORCEPROP 1 LAST PATH I222
J 0
(-3227 2700);
DISPLAY 0.872340 (-3227 2700);
PAINT GREEN (-3227 2700);
DISPLAY INVISIBLE (-3227 2700);
FORCEADD TAP..1
(-3225 2650);
FORCEPROP 3 LASTPIN (-3275 2650) SIG_NAME M_L_CPU0_SB_DQ<28>
J 0
(-3265 2660);
DISPLAY 0.659574 (-3265 2660);
PAINT MONO (-3265 2660);
DISPLAY INVISIBLE (-3265 2660);
FORCEPROP 1 LASTPIN (-3275 2650) BN 28
J 0
(-3287 2658);
DISPLAY 0.489362 (-3287 2658);
PAINT GREEN (-3287 2658);
FORCEPROP 2 LAST CDS_LIB mstr_standard
J 0
(-3225 2650);
DISPLAY 0.723404 (-3225 2650);
PAINT MONO (-3225 2650);
DISPLAY INVISIBLE (-3225 2650);
FORCEPROP 1 LAST BODY_TYPE PLUMBING
J 0
(-3225 2700);
DISPLAY 0.872340 (-3225 2700);
PAINT GREEN (-3225 2700);
DISPLAY INVISIBLE (-3225 2700);
FORCEPROP 1 LAST HDL_TAP TRUE
J 0
(-2900 2525);
DISPLAY 0.872340 (-2900 2525);
DISPLAY INVISIBLE (-2900 2525);
FORCEPROP 1 LAST PATH I223
J 0
(-3227 2650);
DISPLAY 0.872340 (-3227 2650);
PAINT GREEN (-3227 2650);
DISPLAY INVISIBLE (-3227 2650);
FORCEADD TAP..1
(-3225 2600);
FORCEPROP 3 LASTPIN (-3275 2600) SIG_NAME M_L_CPU0_SB_DQ<29>
J 0
(-3265 2610);
DISPLAY 0.659574 (-3265 2610);
PAINT MONO (-3265 2610);
DISPLAY INVISIBLE (-3265 2610);
FORCEPROP 1 LASTPIN (-3275 2600) BN 29
J 0
(-3287 2608);
DISPLAY 0.489362 (-3287 2608);
PAINT GREEN (-3287 2608);
FORCEPROP 2 LAST CDS_LIB mstr_standard
J 0
(-3225 2600);
DISPLAY 0.723404 (-3225 2600);
PAINT MONO (-3225 2600);
DISPLAY INVISIBLE (-3225 2600);
FORCEPROP 1 LAST BODY_TYPE PLUMBING
J 0
(-3225 2650);
DISPLAY 0.872340 (-3225 2650);
PAINT GREEN (-3225 2650);
DISPLAY INVISIBLE (-3225 2650);
FORCEPROP 1 LAST HDL_TAP TRUE
J 0
(-2900 2475);
DISPLAY 0.872340 (-2900 2475);
DISPLAY INVISIBLE (-2900 2475);
FORCEPROP 1 LAST PATH I224
J 0
(-3227 2600);
DISPLAY 0.872340 (-3227 2600);
PAINT GREEN (-3227 2600);
DISPLAY INVISIBLE (-3227 2600);
FORCEADD TAP..1
(-3225 2500);
FORCEPROP 3 LASTPIN (-3275 2500) SIG_NAME M_L_CPU0_SB_DQ<31>
J 0
(-3265 2510);
DISPLAY 0.659574 (-3265 2510);
PAINT MONO (-3265 2510);
DISPLAY INVISIBLE (-3265 2510);
FORCEPROP 1 LASTPIN (-3275 2500) BN 31
J 0
(-3287 2508);
DISPLAY 0.489362 (-3287 2508);
PAINT GREEN (-3287 2508);
FORCEPROP 2 LAST CDS_LIB mstr_standard
J 0
(-3225 2500);
DISPLAY 0.723404 (-3225 2500);
PAINT MONO (-3225 2500);
DISPLAY INVISIBLE (-3225 2500);
FORCEPROP 1 LAST BODY_TYPE PLUMBING
J 0
(-3225 2550);
DISPLAY 0.872340 (-3225 2550);
PAINT GREEN (-3225 2550);
DISPLAY INVISIBLE (-3225 2550);
FORCEPROP 1 LAST HDL_TAP TRUE
J 0
(-2900 2375);
DISPLAY 0.872340 (-2900 2375);
DISPLAY INVISIBLE (-2900 2375);
FORCEPROP 1 LAST PATH I225
J 0
(-3227 2500);
DISPLAY 0.872340 (-3227 2500);
PAINT GREEN (-3227 2500);
DISPLAY INVISIBLE (-3227 2500);
FORCEADD TAP..1
(-3225 2550);
FORCEPROP 3 LASTPIN (-3275 2550) SIG_NAME M_L_CPU0_SB_DQ<30>
J 0
(-3265 2560);
DISPLAY 0.659574 (-3265 2560);
PAINT MONO (-3265 2560);
DISPLAY INVISIBLE (-3265 2560);
FORCEPROP 1 LASTPIN (-3275 2550) BN 30
J 0
(-3287 2558);
DISPLAY 0.489362 (-3287 2558);
PAINT GREEN (-3287 2558);
FORCEPROP 2 LAST CDS_LIB mstr_standard
J 0
(-3225 2550);
DISPLAY 0.723404 (-3225 2550);
PAINT MONO (-3225 2550);
DISPLAY INVISIBLE (-3225 2550);
FORCEPROP 1 LAST BODY_TYPE PLUMBING
J 0
(-3225 2600);
DISPLAY 0.872340 (-3225 2600);
PAINT GREEN (-3225 2600);
DISPLAY INVISIBLE (-3225 2600);
FORCEPROP 1 LAST HDL_TAP TRUE
J 0
(-2900 2425);
DISPLAY 0.872340 (-2900 2425);
DISPLAY INVISIBLE (-2900 2425);
FORCEPROP 1 LAST PATH I226
J 0
(-3227 2550);
DISPLAY 0.872340 (-3227 2550);
PAINT GREEN (-3227 2550);
DISPLAY INVISIBLE (-3227 2550);
FORCEADD TAP..1
(-3225 2400);
FORCEPROP 3 LASTPIN (-3275 2400) SIG_NAME M_L_CPU0_SA_CB<0>
J 0
(-3265 2410);
DISPLAY 0.659574 (-3265 2410);
PAINT MONO (-3265 2410);
DISPLAY INVISIBLE (-3265 2410);
FORCEPROP 1 LASTPIN (-3275 2400) BN 0
J 0
(-3287 2408);
DISPLAY 0.489362 (-3287 2408);
PAINT GREEN (-3287 2408);
FORCEPROP 2 LAST CDS_LIB mstr_standard
J 2
(-3225 2400);
DISPLAY 0.723404 (-3225 2400);
PAINT MONO (-3225 2400);
DISPLAY INVISIBLE (-3225 2400);
FORCEPROP 1 LAST BODY_TYPE PLUMBING
J 0
(-3225 2450);
DISPLAY 0.872340 (-3225 2450);
PAINT GREEN (-3225 2450);
DISPLAY INVISIBLE (-3225 2450);
FORCEPROP 1 LAST HDL_TAP TRUE
J 0
(-2900 2275);
DISPLAY 0.872340 (-2900 2275);
DISPLAY INVISIBLE (-2900 2275);
FORCEPROP 1 LAST PATH I227
J 0
(-3227 2400);
DISPLAY 0.872340 (-3227 2400);
PAINT GREEN (-3227 2400);
DISPLAY INVISIBLE (-3227 2400);
FORCEADD TAP..1
(-3225 2350);
FORCEPROP 3 LASTPIN (-3275 2350) SIG_NAME M_L_CPU0_SA_CB<1>
J 0
(-3265 2360);
DISPLAY 0.659574 (-3265 2360);
PAINT MONO (-3265 2360);
DISPLAY INVISIBLE (-3265 2360);
FORCEPROP 1 LASTPIN (-3275 2350) BN 1
J 0
(-3287 2358);
DISPLAY 0.489362 (-3287 2358);
PAINT GREEN (-3287 2358);
FORCEPROP 2 LAST CDS_LIB mstr_standard
J 2
(-3225 2350);
DISPLAY 0.723404 (-3225 2350);
PAINT MONO (-3225 2350);
DISPLAY INVISIBLE (-3225 2350);
FORCEPROP 1 LAST BODY_TYPE PLUMBING
J 0
(-3225 2400);
DISPLAY 0.872340 (-3225 2400);
PAINT GREEN (-3225 2400);
DISPLAY INVISIBLE (-3225 2400);
FORCEPROP 1 LAST HDL_TAP TRUE
J 0
(-2900 2225);
DISPLAY 0.872340 (-2900 2225);
DISPLAY INVISIBLE (-2900 2225);
FORCEPROP 1 LAST PATH I228
J 0
(-3227 2350);
DISPLAY 0.872340 (-3227 2350);
PAINT GREEN (-3227 2350);
DISPLAY INVISIBLE (-3227 2350);
FORCEADD TAP..1
(-3225 2300);
FORCEPROP 3 LASTPIN (-3275 2300) SIG_NAME M_L_CPU0_SA_CB<2>
J 0
(-3265 2310);
DISPLAY 0.659574 (-3265 2310);
PAINT MONO (-3265 2310);
DISPLAY INVISIBLE (-3265 2310);
FORCEPROP 1 LASTPIN (-3275 2300) BN 2
J 0
(-3287 2308);
DISPLAY 0.489362 (-3287 2308);
PAINT GREEN (-3287 2308);
FORCEPROP 2 LAST CDS_LIB mstr_standard
J 2
(-3225 2300);
DISPLAY 0.723404 (-3225 2300);
PAINT MONO (-3225 2300);
DISPLAY INVISIBLE (-3225 2300);
FORCEPROP 1 LAST BODY_TYPE PLUMBING
J 0
(-3225 2350);
DISPLAY 0.872340 (-3225 2350);
PAINT GREEN (-3225 2350);
DISPLAY INVISIBLE (-3225 2350);
FORCEPROP 1 LAST HDL_TAP TRUE
J 0
(-2900 2175);
DISPLAY 0.872340 (-2900 2175);
DISPLAY INVISIBLE (-2900 2175);
FORCEPROP 1 LAST PATH I229
J 0
(-3227 2300);
DISPLAY 0.872340 (-3227 2300);
PAINT GREEN (-3227 2300);
DISPLAY INVISIBLE (-3227 2300);
FORCEADD TAP..1
(-3225 2250);
FORCEPROP 3 LASTPIN (-3275 2250) SIG_NAME M_L_CPU0_SA_CB<3>
J 0
(-3265 2260);
DISPLAY 0.659574 (-3265 2260);
PAINT MONO (-3265 2260);
DISPLAY INVISIBLE (-3265 2260);
FORCEPROP 1 LASTPIN (-3275 2250) BN 3
J 0
(-3287 2258);
DISPLAY 0.489362 (-3287 2258);
PAINT GREEN (-3287 2258);
FORCEPROP 2 LAST CDS_LIB mstr_standard
J 2
(-3225 2250);
DISPLAY 0.723404 (-3225 2250);
PAINT MONO (-3225 2250);
DISPLAY INVISIBLE (-3225 2250);
FORCEPROP 1 LAST BODY_TYPE PLUMBING
J 0
(-3225 2300);
DISPLAY 0.872340 (-3225 2300);
PAINT GREEN (-3225 2300);
DISPLAY INVISIBLE (-3225 2300);
FORCEPROP 1 LAST HDL_TAP TRUE
J 0
(-2900 2125);
DISPLAY 0.872340 (-2900 2125);
DISPLAY INVISIBLE (-2900 2125);
FORCEPROP 1 LAST PATH I230
J 0
(-3227 2250);
DISPLAY 0.872340 (-3227 2250);
PAINT GREEN (-3227 2250);
DISPLAY INVISIBLE (-3227 2250);
FORCEADD TAP..1
(-3225 2200);
FORCEPROP 3 LASTPIN (-3275 2200) SIG_NAME M_L_CPU0_SA_CB<4>
J 0
(-3265 2210);
DISPLAY 0.659574 (-3265 2210);
PAINT MONO (-3265 2210);
DISPLAY INVISIBLE (-3265 2210);
FORCEPROP 1 LASTPIN (-3275 2200) BN 4
J 0
(-3287 2208);
DISPLAY 0.489362 (-3287 2208);
PAINT GREEN (-3287 2208);
FORCEPROP 2 LAST CDS_LIB mstr_standard
J 2
(-3225 2200);
DISPLAY 0.723404 (-3225 2200);
PAINT MONO (-3225 2200);
DISPLAY INVISIBLE (-3225 2200);
FORCEPROP 1 LAST BODY_TYPE PLUMBING
J 0
(-3225 2250);
DISPLAY 0.872340 (-3225 2250);
PAINT GREEN (-3225 2250);
DISPLAY INVISIBLE (-3225 2250);
FORCEPROP 1 LAST HDL_TAP TRUE
J 0
(-2900 2075);
DISPLAY 0.872340 (-2900 2075);
DISPLAY INVISIBLE (-2900 2075);
FORCEPROP 1 LAST PATH I231
J 0
(-3227 2200);
DISPLAY 0.872340 (-3227 2200);
PAINT GREEN (-3227 2200);
DISPLAY INVISIBLE (-3227 2200);
FORCEADD TAP..1
(-3225 2100);
FORCEPROP 3 LASTPIN (-3275 2100) SIG_NAME M_L_CPU0_SA_CB<6>
J 0
(-3265 2110);
DISPLAY 0.659574 (-3265 2110);
PAINT MONO (-3265 2110);
DISPLAY INVISIBLE (-3265 2110);
FORCEPROP 1 LASTPIN (-3275 2100) BN 6
J 0
(-3287 2108);
DISPLAY 0.489362 (-3287 2108);
PAINT GREEN (-3287 2108);
FORCEPROP 2 LAST CDS_LIB mstr_standard
J 2
(-3225 2100);
DISPLAY 0.723404 (-3225 2100);
PAINT MONO (-3225 2100);
DISPLAY INVISIBLE (-3225 2100);
FORCEPROP 1 LAST BODY_TYPE PLUMBING
J 0
(-3225 2150);
DISPLAY 0.872340 (-3225 2150);
PAINT GREEN (-3225 2150);
DISPLAY INVISIBLE (-3225 2150);
FORCEPROP 1 LAST HDL_TAP TRUE
J 0
(-2900 1975);
DISPLAY 0.872340 (-2900 1975);
DISPLAY INVISIBLE (-2900 1975);
FORCEPROP 1 LAST PATH I232
J 0
(-3227 2100);
DISPLAY 0.872340 (-3227 2100);
PAINT GREEN (-3227 2100);
DISPLAY INVISIBLE (-3227 2100);
FORCEADD TAP..1
(-3225 2150);
FORCEPROP 3 LASTPIN (-3275 2150) SIG_NAME M_L_CPU0_SA_CB<5>
J 0
(-3265 2160);
DISPLAY 0.659574 (-3265 2160);
PAINT MONO (-3265 2160);
DISPLAY INVISIBLE (-3265 2160);
FORCEPROP 1 LASTPIN (-3275 2150) BN 5
J 0
(-3287 2158);
DISPLAY 0.489362 (-3287 2158);
PAINT GREEN (-3287 2158);
FORCEPROP 2 LAST CDS_LIB mstr_standard
J 2
(-3225 2150);
DISPLAY 0.723404 (-3225 2150);
PAINT MONO (-3225 2150);
DISPLAY INVISIBLE (-3225 2150);
FORCEPROP 1 LAST BODY_TYPE PLUMBING
J 0
(-3225 2200);
DISPLAY 0.872340 (-3225 2200);
PAINT GREEN (-3225 2200);
DISPLAY INVISIBLE (-3225 2200);
FORCEPROP 1 LAST HDL_TAP TRUE
J 0
(-2900 2025);
DISPLAY 0.872340 (-2900 2025);
DISPLAY INVISIBLE (-2900 2025);
FORCEPROP 1 LAST PATH I233
J 0
(-3227 2150);
DISPLAY 0.872340 (-3227 2150);
PAINT GREEN (-3227 2150);
DISPLAY INVISIBLE (-3227 2150);
FORCEADD TAP..1
(-3225 2050);
FORCEPROP 3 LASTPIN (-3275 2050) SIG_NAME M_L_CPU0_SA_CB<7>
J 0
(-3265 2060);
DISPLAY 0.659574 (-3265 2060);
PAINT MONO (-3265 2060);
DISPLAY INVISIBLE (-3265 2060);
FORCEPROP 1 LASTPIN (-3275 2050) BN 7
J 0
(-3287 2058);
DISPLAY 0.489362 (-3287 2058);
PAINT GREEN (-3287 2058);
FORCEPROP 2 LAST CDS_LIB mstr_standard
J 2
(-3225 2050);
DISPLAY 0.723404 (-3225 2050);
PAINT MONO (-3225 2050);
DISPLAY INVISIBLE (-3225 2050);
FORCEPROP 1 LAST BODY_TYPE PLUMBING
J 0
(-3225 2100);
DISPLAY 0.872340 (-3225 2100);
PAINT GREEN (-3225 2100);
DISPLAY INVISIBLE (-3225 2100);
FORCEPROP 1 LAST HDL_TAP TRUE
J 0
(-2900 1925);
DISPLAY 0.872340 (-2900 1925);
DISPLAY INVISIBLE (-2900 1925);
FORCEPROP 1 LAST PATH I234
J 0
(-3227 2050);
DISPLAY 0.872340 (-3227 2050);
PAINT GREEN (-3227 2050);
DISPLAY INVISIBLE (-3227 2050);
FORCEADD OFFPAGE..6
R 2
(-2625 2000);
FORCEPROP 2 LAST $XR0 97 
J 0
(-2411 2000);
DISPLAY 0.638298 (-2411 2000);
PAINT MONO (-2411 2000);
FORCEPROP 2 LAST CDS_LIB mstr_standard
J 2
(-2625 2000);
DISPLAY 0.723404 (-2625 2000);
PAINT MONO (-2625 2000);
DISPLAY INVISIBLE (-2625 2000);
FORCEPROP 1 LAST OFFPAGE TRUE
J 2
(-2950 1875);
DISPLAY 0.872340 (-2950 1875);
PAINT GREEN (-2950 1875);
DISPLAY INVISIBLE (-2950 1875);
FORCEPROP 1 LAST COMMENT_BODY TRUE
J 2
(-2725 1925);
DISPLAY 0.872340 (-2725 1925);
PAINT GREEN (-2725 1925);
DISPLAY INVISIBLE (-2725 1925);
FORCEPROP 2 LAST PATH I235
J 0
(-2400 2050);
DISPLAY 1.021277 (-2400 2050);
DISPLAY INVISIBLE (-2400 2050);
FORCEADD TAP..1
(-3225 1850);
FORCEPROP 3 LASTPIN (-3275 1850) SIG_NAME M_L_CPU0_SB_CB<2>
J 0
(-3265 1860);
DISPLAY 0.659574 (-3265 1860);
PAINT MONO (-3265 1860);
DISPLAY INVISIBLE (-3265 1860);
FORCEPROP 1 LASTPIN (-3275 1850) BN 2
J 0
(-3287 1858);
DISPLAY 0.489362 (-3287 1858);
PAINT GREEN (-3287 1858);
FORCEPROP 2 LAST CDS_LIB mstr_standard
J 2
(-3225 1850);
DISPLAY 0.723404 (-3225 1850);
PAINT MONO (-3225 1850);
DISPLAY INVISIBLE (-3225 1850);
FORCEPROP 1 LAST BODY_TYPE PLUMBING
J 0
(-3225 1900);
DISPLAY 0.872340 (-3225 1900);
PAINT GREEN (-3225 1900);
DISPLAY INVISIBLE (-3225 1900);
FORCEPROP 1 LAST HDL_TAP TRUE
J 0
(-2900 1725);
DISPLAY 0.872340 (-2900 1725);
DISPLAY INVISIBLE (-2900 1725);
FORCEPROP 1 LAST PATH I236
J 0
(-3227 1850);
DISPLAY 0.872340 (-3227 1850);
PAINT GREEN (-3227 1850);
DISPLAY INVISIBLE (-3227 1850);
FORCEADD TAP..1
(-3225 1900);
FORCEPROP 3 LASTPIN (-3275 1900) SIG_NAME M_L_CPU0_SB_CB<1>
J 0
(-3265 1910);
DISPLAY 0.659574 (-3265 1910);
PAINT MONO (-3265 1910);
DISPLAY INVISIBLE (-3265 1910);
FORCEPROP 1 LASTPIN (-3275 1900) BN 1
J 0
(-3287 1908);
DISPLAY 0.489362 (-3287 1908);
PAINT GREEN (-3287 1908);
FORCEPROP 2 LAST CDS_LIB mstr_standard
J 2
(-3225 1900);
DISPLAY 0.723404 (-3225 1900);
PAINT MONO (-3225 1900);
DISPLAY INVISIBLE (-3225 1900);
FORCEPROP 1 LAST BODY_TYPE PLUMBING
J 0
(-3225 1950);
DISPLAY 0.872340 (-3225 1950);
PAINT GREEN (-3225 1950);
DISPLAY INVISIBLE (-3225 1950);
FORCEPROP 1 LAST HDL_TAP TRUE
J 0
(-2900 1775);
DISPLAY 0.872340 (-2900 1775);
DISPLAY INVISIBLE (-2900 1775);
FORCEPROP 1 LAST PATH I237
J 0
(-3227 1900);
DISPLAY 0.872340 (-3227 1900);
PAINT GREEN (-3227 1900);
DISPLAY INVISIBLE (-3227 1900);
FORCEADD TAP..1
(-3225 1950);
FORCEPROP 3 LASTPIN (-3275 1950) SIG_NAME M_L_CPU0_SB_CB<0>
J 0
(-3265 1960);
DISPLAY 0.659574 (-3265 1960);
PAINT MONO (-3265 1960);
DISPLAY INVISIBLE (-3265 1960);
FORCEPROP 1 LASTPIN (-3275 1950) BN 0
J 0
(-3287 1958);
DISPLAY 0.489362 (-3287 1958);
PAINT GREEN (-3287 1958);
FORCEPROP 2 LAST CDS_LIB mstr_standard
J 2
(-3225 1950);
DISPLAY 0.723404 (-3225 1950);
PAINT MONO (-3225 1950);
DISPLAY INVISIBLE (-3225 1950);
FORCEPROP 1 LAST BODY_TYPE PLUMBING
J 0
(-3225 2000);
DISPLAY 0.872340 (-3225 2000);
PAINT GREEN (-3225 2000);
DISPLAY INVISIBLE (-3225 2000);
FORCEPROP 1 LAST HDL_TAP TRUE
J 0
(-2900 1825);
DISPLAY 0.872340 (-2900 1825);
DISPLAY INVISIBLE (-2900 1825);
FORCEPROP 1 LAST PATH I238
J 0
(-3227 1950);
DISPLAY 0.872340 (-3227 1950);
PAINT GREEN (-3227 1950);
DISPLAY INVISIBLE (-3227 1950);
FORCEADD TAP..1
(-3225 1800);
FORCEPROP 3 LASTPIN (-3275 1800) SIG_NAME M_L_CPU0_SB_CB<3>
J 0
(-3265 1810);
DISPLAY 0.659574 (-3265 1810);
PAINT MONO (-3265 1810);
DISPLAY INVISIBLE (-3265 1810);
FORCEPROP 1 LASTPIN (-3275 1800) BN 3
J 0
(-3287 1808);
DISPLAY 0.489362 (-3287 1808);
PAINT GREEN (-3287 1808);
FORCEPROP 2 LAST CDS_LIB mstr_standard
J 2
(-3225 1800);
DISPLAY 0.723404 (-3225 1800);
PAINT MONO (-3225 1800);
DISPLAY INVISIBLE (-3225 1800);
FORCEPROP 1 LAST BODY_TYPE PLUMBING
J 0
(-3225 1850);
DISPLAY 0.872340 (-3225 1850);
PAINT GREEN (-3225 1850);
DISPLAY INVISIBLE (-3225 1850);
FORCEPROP 1 LAST HDL_TAP TRUE
J 0
(-2900 1675);
DISPLAY 0.872340 (-2900 1675);
DISPLAY INVISIBLE (-2900 1675);
FORCEPROP 1 LAST PATH I239
J 0
(-3227 1800);
DISPLAY 0.872340 (-3227 1800);
PAINT GREEN (-3227 1800);
DISPLAY INVISIBLE (-3227 1800);
FORCEADD TAP..1
(-3225 1750);
FORCEPROP 3 LASTPIN (-3275 1750) SIG_NAME M_L_CPU0_SB_CB<4>
J 0
(-3265 1760);
DISPLAY 0.659574 (-3265 1760);
PAINT MONO (-3265 1760);
DISPLAY INVISIBLE (-3265 1760);
FORCEPROP 1 LASTPIN (-3275 1750) BN 4
J 0
(-3287 1758);
DISPLAY 0.489362 (-3287 1758);
PAINT GREEN (-3287 1758);
FORCEPROP 2 LAST CDS_LIB mstr_standard
J 2
(-3225 1750);
DISPLAY 0.723404 (-3225 1750);
PAINT MONO (-3225 1750);
DISPLAY INVISIBLE (-3225 1750);
FORCEPROP 1 LAST BODY_TYPE PLUMBING
J 0
(-3225 1800);
DISPLAY 0.872340 (-3225 1800);
PAINT GREEN (-3225 1800);
DISPLAY INVISIBLE (-3225 1800);
FORCEPROP 1 LAST HDL_TAP TRUE
J 0
(-2900 1625);
DISPLAY 0.872340 (-2900 1625);
DISPLAY INVISIBLE (-2900 1625);
FORCEPROP 1 LAST PATH I240
J 0
(-3227 1750);
DISPLAY 0.872340 (-3227 1750);
PAINT GREEN (-3227 1750);
DISPLAY INVISIBLE (-3227 1750);
FORCEADD TAP..1
(-3225 1600);
FORCEPROP 3 LASTPIN (-3275 1600) SIG_NAME M_L_CPU0_SB_CB<7>
J 0
(-3265 1610);
DISPLAY 0.659574 (-3265 1610);
PAINT MONO (-3265 1610);
DISPLAY INVISIBLE (-3265 1610);
FORCEPROP 1 LASTPIN (-3275 1600) BN 7
J 0
(-3287 1608);
DISPLAY 0.489362 (-3287 1608);
PAINT GREEN (-3287 1608);
FORCEPROP 2 LAST CDS_LIB mstr_standard
J 2
(-3225 1600);
DISPLAY 0.723404 (-3225 1600);
PAINT MONO (-3225 1600);
DISPLAY INVISIBLE (-3225 1600);
FORCEPROP 1 LAST BODY_TYPE PLUMBING
J 0
(-3225 1650);
DISPLAY 0.872340 (-3225 1650);
PAINT GREEN (-3225 1650);
DISPLAY INVISIBLE (-3225 1650);
FORCEPROP 1 LAST HDL_TAP TRUE
J 0
(-2900 1475);
DISPLAY 0.872340 (-2900 1475);
DISPLAY INVISIBLE (-2900 1475);
FORCEPROP 1 LAST PATH I241
J 0
(-3227 1600);
DISPLAY 0.872340 (-3227 1600);
PAINT GREEN (-3227 1600);
DISPLAY INVISIBLE (-3227 1600);
FORCEADD TAP..1
(-3225 1650);
FORCEPROP 3 LASTPIN (-3275 1650) SIG_NAME M_L_CPU0_SB_CB<6>
J 0
(-3265 1660);
DISPLAY 0.659574 (-3265 1660);
PAINT MONO (-3265 1660);
DISPLAY INVISIBLE (-3265 1660);
FORCEPROP 1 LASTPIN (-3275 1650) BN 6
J 0
(-3287 1658);
DISPLAY 0.489362 (-3287 1658);
PAINT GREEN (-3287 1658);
FORCEPROP 2 LAST CDS_LIB mstr_standard
J 2
(-3225 1650);
DISPLAY 0.723404 (-3225 1650);
PAINT MONO (-3225 1650);
DISPLAY INVISIBLE (-3225 1650);
FORCEPROP 1 LAST BODY_TYPE PLUMBING
J 0
(-3225 1700);
DISPLAY 0.872340 (-3225 1700);
PAINT GREEN (-3225 1700);
DISPLAY INVISIBLE (-3225 1700);
FORCEPROP 1 LAST HDL_TAP TRUE
J 0
(-2900 1525);
DISPLAY 0.872340 (-2900 1525);
DISPLAY INVISIBLE (-2900 1525);
FORCEPROP 1 LAST PATH I242
J 0
(-3227 1650);
DISPLAY 0.872340 (-3227 1650);
PAINT GREEN (-3227 1650);
DISPLAY INVISIBLE (-3227 1650);
FORCEADD TAP..1
(-3225 1700);
FORCEPROP 3 LASTPIN (-3275 1700) SIG_NAME M_L_CPU0_SB_CB<5>
J 0
(-3265 1710);
DISPLAY 0.659574 (-3265 1710);
PAINT MONO (-3265 1710);
DISPLAY INVISIBLE (-3265 1710);
FORCEPROP 1 LASTPIN (-3275 1700) BN 5
J 0
(-3287 1708);
DISPLAY 0.489362 (-3287 1708);
PAINT GREEN (-3287 1708);
FORCEPROP 2 LAST CDS_LIB mstr_standard
J 2
(-3225 1700);
DISPLAY 0.723404 (-3225 1700);
PAINT MONO (-3225 1700);
DISPLAY INVISIBLE (-3225 1700);
FORCEPROP 1 LAST BODY_TYPE PLUMBING
J 0
(-3225 1750);
DISPLAY 0.872340 (-3225 1750);
PAINT GREEN (-3225 1750);
DISPLAY INVISIBLE (-3225 1750);
FORCEPROP 1 LAST HDL_TAP TRUE
J 0
(-2900 1575);
DISPLAY 0.872340 (-2900 1575);
DISPLAY INVISIBLE (-2900 1575);
FORCEPROP 1 LAST PATH I243
J 0
(-3227 1700);
DISPLAY 0.872340 (-3227 1700);
PAINT GREEN (-3227 1700);
DISPLAY INVISIBLE (-3227 1700);
FORCEADD TAP..1
R 2
(-5650 6000);
FORCEPROP 3 LASTPIN (-5600 6000) SIG_NAME M_L_CPU0_SA_DQS_DP<0>
J 0
(-5590 6010);
DISPLAY 0.659574 (-5590 6010);
PAINT MONO (-5590 6010);
DISPLAY INVISIBLE (-5590 6010);
FORCEPROP 1 LASTPIN (-5600 6000) BN 0
J 2
(-5588 6008);
DISPLAY 0.489362 (-5588 6008);
PAINT GREEN (-5588 6008);
FORCEPROP 2 LAST CDS_LIB mstr_standard
J 2
(-5650 6000);
DISPLAY 0.723404 (-5650 6000);
PAINT MONO (-5650 6000);
DISPLAY INVISIBLE (-5650 6000);
FORCEPROP 1 LAST BODY_TYPE PLUMBING
J 2
(-5650 6050);
DISPLAY 0.872340 (-5650 6050);
PAINT GREEN (-5650 6050);
DISPLAY INVISIBLE (-5650 6050);
FORCEPROP 1 LAST HDL_TAP TRUE
J 2
(-5975 5875);
DISPLAY 0.872340 (-5975 5875);
DISPLAY INVISIBLE (-5975 5875);
FORCEPROP 1 LAST PATH I244
J 2
(-5648 6000);
DISPLAY 0.872340 (-5648 6000);
PAINT GREEN (-5648 6000);
DISPLAY INVISIBLE (-5648 6000);
FORCEADD TAP..1
R 2
(-5650 5900);
FORCEPROP 3 LASTPIN (-5600 5900) SIG_NAME M_L_CPU0_SA_DQS_DP<1>
J 0
(-5590 5910);
DISPLAY 0.659574 (-5590 5910);
PAINT MONO (-5590 5910);
DISPLAY INVISIBLE (-5590 5910);
FORCEPROP 1 LASTPIN (-5600 5900) BN 1
J 2
(-5588 5908);
DISPLAY 0.489362 (-5588 5908);
PAINT GREEN (-5588 5908);
FORCEPROP 2 LAST CDS_LIB mstr_standard
J 2
(-5650 5900);
DISPLAY 0.723404 (-5650 5900);
PAINT MONO (-5650 5900);
DISPLAY INVISIBLE (-5650 5900);
FORCEPROP 1 LAST BODY_TYPE PLUMBING
J 2
(-5650 5950);
DISPLAY 0.872340 (-5650 5950);
PAINT GREEN (-5650 5950);
DISPLAY INVISIBLE (-5650 5950);
FORCEPROP 1 LAST HDL_TAP TRUE
J 2
(-5975 5775);
DISPLAY 0.872340 (-5975 5775);
DISPLAY INVISIBLE (-5975 5775);
FORCEPROP 1 LAST PATH I245
J 2
(-5648 5900);
DISPLAY 0.872340 (-5648 5900);
PAINT GREEN (-5648 5900);
DISPLAY INVISIBLE (-5648 5900);
FORCEADD TAP..1
R 2
(-5650 5800);
FORCEPROP 3 LASTPIN (-5600 5800) SIG_NAME M_L_CPU0_SA_DQS_DP<2>
J 0
(-5590 5810);
DISPLAY 0.659574 (-5590 5810);
PAINT MONO (-5590 5810);
DISPLAY INVISIBLE (-5590 5810);
FORCEPROP 1 LASTPIN (-5600 5800) BN 2
J 2
(-5588 5808);
DISPLAY 0.489362 (-5588 5808);
PAINT GREEN (-5588 5808);
FORCEPROP 2 LAST CDS_LIB mstr_standard
J 2
(-5650 5800);
DISPLAY 0.723404 (-5650 5800);
PAINT MONO (-5650 5800);
DISPLAY INVISIBLE (-5650 5800);
FORCEPROP 1 LAST BODY_TYPE PLUMBING
J 2
(-5650 5850);
DISPLAY 0.872340 (-5650 5850);
PAINT GREEN (-5650 5850);
DISPLAY INVISIBLE (-5650 5850);
FORCEPROP 1 LAST HDL_TAP TRUE
J 2
(-5975 5675);
DISPLAY 0.872340 (-5975 5675);
DISPLAY INVISIBLE (-5975 5675);
FORCEPROP 1 LAST PATH I246
J 2
(-5648 5800);
DISPLAY 0.872340 (-5648 5800);
PAINT GREEN (-5648 5800);
DISPLAY INVISIBLE (-5648 5800);
FORCEADD TAP..1
R 2
(-5650 5700);
FORCEPROP 3 LASTPIN (-5600 5700) SIG_NAME M_L_CPU0_SA_DQS_DP<3>
J 0
(-5590 5710);
DISPLAY 0.659574 (-5590 5710);
PAINT MONO (-5590 5710);
DISPLAY INVISIBLE (-5590 5710);
FORCEPROP 1 LASTPIN (-5600 5700) BN 3
J 2
(-5588 5708);
DISPLAY 0.489362 (-5588 5708);
PAINT GREEN (-5588 5708);
FORCEPROP 2 LAST CDS_LIB mstr_standard
J 2
(-5650 5700);
DISPLAY 0.723404 (-5650 5700);
PAINT MONO (-5650 5700);
DISPLAY INVISIBLE (-5650 5700);
FORCEPROP 1 LAST BODY_TYPE PLUMBING
J 2
(-5650 5750);
DISPLAY 0.872340 (-5650 5750);
PAINT GREEN (-5650 5750);
DISPLAY INVISIBLE (-5650 5750);
FORCEPROP 1 LAST HDL_TAP TRUE
J 2
(-5975 5575);
DISPLAY 0.872340 (-5975 5575);
DISPLAY INVISIBLE (-5975 5575);
FORCEPROP 1 LAST PATH I247
J 2
(-5648 5700);
DISPLAY 0.872340 (-5648 5700);
PAINT GREEN (-5648 5700);
DISPLAY INVISIBLE (-5648 5700);
FORCEADD TAP..1
R 2
(-5650 5600);
FORCEPROP 3 LASTPIN (-5600 5600) SIG_NAME M_L_CPU0_SA_DQS_DP<4>
J 0
(-5590 5610);
DISPLAY 0.659574 (-5590 5610);
PAINT MONO (-5590 5610);
DISPLAY INVISIBLE (-5590 5610);
FORCEPROP 1 LASTPIN (-5600 5600) BN 4
J 2
(-5588 5608);
DISPLAY 0.489362 (-5588 5608);
PAINT GREEN (-5588 5608);
FORCEPROP 2 LAST CDS_LIB mstr_standard
J 2
(-5650 5600);
DISPLAY 0.723404 (-5650 5600);
PAINT MONO (-5650 5600);
DISPLAY INVISIBLE (-5650 5600);
FORCEPROP 1 LAST BODY_TYPE PLUMBING
J 2
(-5650 5650);
DISPLAY 0.872340 (-5650 5650);
PAINT GREEN (-5650 5650);
DISPLAY INVISIBLE (-5650 5650);
FORCEPROP 1 LAST HDL_TAP TRUE
J 2
(-5975 5475);
DISPLAY 0.872340 (-5975 5475);
DISPLAY INVISIBLE (-5975 5475);
FORCEPROP 1 LAST PATH I248
J 2
(-5648 5600);
DISPLAY 0.872340 (-5648 5600);
PAINT GREEN (-5648 5600);
DISPLAY INVISIBLE (-5648 5600);
FORCEADD TAP..1
R 2
(-5650 5400);
FORCEPROP 3 LASTPIN (-5600 5400) SIG_NAME M_L_CPU0_SA_DQS_DP<6>
J 0
(-5590 5410);
DISPLAY 0.659574 (-5590 5410);
PAINT MONO (-5590 5410);
DISPLAY INVISIBLE (-5590 5410);
FORCEPROP 1 LASTPIN (-5600 5400) BN 6
J 2
(-5588 5408);
DISPLAY 0.489362 (-5588 5408);
PAINT GREEN (-5588 5408);
FORCEPROP 2 LAST CDS_LIB mstr_standard
J 2
(-5650 5400);
DISPLAY 0.723404 (-5650 5400);
PAINT MONO (-5650 5400);
DISPLAY INVISIBLE (-5650 5400);
FORCEPROP 1 LAST BODY_TYPE PLUMBING
J 2
(-5650 5450);
DISPLAY 0.872340 (-5650 5450);
PAINT GREEN (-5650 5450);
DISPLAY INVISIBLE (-5650 5450);
FORCEPROP 1 LAST HDL_TAP TRUE
J 2
(-5975 5275);
DISPLAY 0.872340 (-5975 5275);
DISPLAY INVISIBLE (-5975 5275);
FORCEPROP 1 LAST PATH I249
J 2
(-5648 5400);
DISPLAY 0.872340 (-5648 5400);
PAINT GREEN (-5648 5400);
DISPLAY INVISIBLE (-5648 5400);
FORCEADD TAP..1
R 2
(-5650 5500);
FORCEPROP 3 LASTPIN (-5600 5500) SIG_NAME M_L_CPU0_SA_DQS_DP<5>
J 0
(-5590 5510);
DISPLAY 0.659574 (-5590 5510);
PAINT MONO (-5590 5510);
DISPLAY INVISIBLE (-5590 5510);
FORCEPROP 1 LASTPIN (-5600 5500) BN 5
J 2
(-5588 5508);
DISPLAY 0.489362 (-5588 5508);
PAINT GREEN (-5588 5508);
FORCEPROP 2 LAST CDS_LIB mstr_standard
J 2
(-5650 5500);
DISPLAY 0.723404 (-5650 5500);
PAINT MONO (-5650 5500);
DISPLAY INVISIBLE (-5650 5500);
FORCEPROP 1 LAST BODY_TYPE PLUMBING
J 2
(-5650 5550);
DISPLAY 0.872340 (-5650 5550);
PAINT GREEN (-5650 5550);
DISPLAY INVISIBLE (-5650 5550);
FORCEPROP 1 LAST HDL_TAP TRUE
J 2
(-5975 5375);
DISPLAY 0.872340 (-5975 5375);
DISPLAY INVISIBLE (-5975 5375);
FORCEPROP 1 LAST PATH I250
J 2
(-5648 5500);
DISPLAY 0.872340 (-5648 5500);
PAINT GREEN (-5648 5500);
DISPLAY INVISIBLE (-5648 5500);
FORCEADD TAP..1
R 2
(-5650 5300);
FORCEPROP 3 LASTPIN (-5600 5300) SIG_NAME M_L_CPU0_SA_DQS_DP<7>
J 0
(-5590 5310);
DISPLAY 0.659574 (-5590 5310);
PAINT MONO (-5590 5310);
DISPLAY INVISIBLE (-5590 5310);
FORCEPROP 1 LASTPIN (-5600 5300) BN 7
J 2
(-5588 5308);
DISPLAY 0.489362 (-5588 5308);
PAINT GREEN (-5588 5308);
FORCEPROP 2 LAST CDS_LIB mstr_standard
J 2
(-5650 5300);
DISPLAY 0.723404 (-5650 5300);
PAINT MONO (-5650 5300);
DISPLAY INVISIBLE (-5650 5300);
FORCEPROP 1 LAST BODY_TYPE PLUMBING
J 2
(-5650 5350);
DISPLAY 0.872340 (-5650 5350);
PAINT GREEN (-5650 5350);
DISPLAY INVISIBLE (-5650 5350);
FORCEPROP 1 LAST HDL_TAP TRUE
J 2
(-5975 5175);
DISPLAY 0.872340 (-5975 5175);
DISPLAY INVISIBLE (-5975 5175);
FORCEPROP 1 LAST PATH I251
J 2
(-5648 5300);
DISPLAY 0.872340 (-5648 5300);
PAINT GREEN (-5648 5300);
DISPLAY INVISIBLE (-5648 5300);
FORCEADD TAP..1
R 2
(-5650 5200);
FORCEPROP 3 LASTPIN (-5600 5200) SIG_NAME M_L_CPU0_SA_DQS_DP<8>
J 0
(-5590 5210);
DISPLAY 0.659574 (-5590 5210);
PAINT MONO (-5590 5210);
DISPLAY INVISIBLE (-5590 5210);
FORCEPROP 1 LASTPIN (-5600 5200) BN 8
J 2
(-5588 5208);
DISPLAY 0.489362 (-5588 5208);
PAINT GREEN (-5588 5208);
FORCEPROP 2 LAST CDS_LIB mstr_standard
J 2
(-5650 5200);
DISPLAY 0.723404 (-5650 5200);
PAINT MONO (-5650 5200);
DISPLAY INVISIBLE (-5650 5200);
FORCEPROP 1 LAST BODY_TYPE PLUMBING
J 2
(-5650 5250);
DISPLAY 0.872340 (-5650 5250);
PAINT GREEN (-5650 5250);
DISPLAY INVISIBLE (-5650 5250);
FORCEPROP 1 LAST HDL_TAP TRUE
J 2
(-5975 5075);
DISPLAY 0.872340 (-5975 5075);
DISPLAY INVISIBLE (-5975 5075);
FORCEPROP 1 LAST PATH I252
J 2
(-5648 5200);
DISPLAY 0.872340 (-5648 5200);
PAINT GREEN (-5648 5200);
DISPLAY INVISIBLE (-5648 5200);
FORCEADD TAP..1
R 2
(-5850 5950);
FORCEPROP 3 LASTPIN (-5800 5950) SIG_NAME M_L_CPU0_SA_DQS_DN<0>
J 0
(-5790 5960);
DISPLAY 0.659574 (-5790 5960);
PAINT MONO (-5790 5960);
DISPLAY INVISIBLE (-5790 5960);
FORCEPROP 1 LASTPIN (-5800 5950) BN 0
J 2
(-5788 5958);
DISPLAY 0.489362 (-5788 5958);
PAINT GREEN (-5788 5958);
FORCEPROP 2 LAST CDS_LIB mstr_standard
J 2
(-5850 5950);
DISPLAY 0.723404 (-5850 5950);
PAINT MONO (-5850 5950);
DISPLAY INVISIBLE (-5850 5950);
FORCEPROP 1 LAST BODY_TYPE PLUMBING
J 2
(-5850 6000);
DISPLAY 0.872340 (-5850 6000);
PAINT GREEN (-5850 6000);
DISPLAY INVISIBLE (-5850 6000);
FORCEPROP 1 LAST HDL_TAP TRUE
J 2
(-6175 5825);
DISPLAY 0.872340 (-6175 5825);
DISPLAY INVISIBLE (-6175 5825);
FORCEPROP 1 LAST PATH I253
J 2
(-5848 5950);
DISPLAY 0.872340 (-5848 5950);
PAINT GREEN (-5848 5950);
DISPLAY INVISIBLE (-5848 5950);
FORCEADD TAP..1
R 2
(-5850 5850);
FORCEPROP 3 LASTPIN (-5800 5850) SIG_NAME M_L_CPU0_SA_DQS_DN<1>
J 0
(-5790 5860);
DISPLAY 0.659574 (-5790 5860);
PAINT MONO (-5790 5860);
DISPLAY INVISIBLE (-5790 5860);
FORCEPROP 1 LASTPIN (-5800 5850) BN 1
J 2
(-5788 5858);
DISPLAY 0.489362 (-5788 5858);
PAINT GREEN (-5788 5858);
FORCEPROP 2 LAST CDS_LIB mstr_standard
J 2
(-5850 5850);
DISPLAY 0.723404 (-5850 5850);
PAINT MONO (-5850 5850);
DISPLAY INVISIBLE (-5850 5850);
FORCEPROP 1 LAST BODY_TYPE PLUMBING
J 2
(-5850 5900);
DISPLAY 0.872340 (-5850 5900);
PAINT GREEN (-5850 5900);
DISPLAY INVISIBLE (-5850 5900);
FORCEPROP 1 LAST HDL_TAP TRUE
J 2
(-6175 5725);
DISPLAY 0.872340 (-6175 5725);
DISPLAY INVISIBLE (-6175 5725);
FORCEPROP 1 LAST PATH I254
J 2
(-5848 5850);
DISPLAY 0.872340 (-5848 5850);
PAINT GREEN (-5848 5850);
DISPLAY INVISIBLE (-5848 5850);
FORCEADD TAP..1
R 2
(-5850 5750);
FORCEPROP 3 LASTPIN (-5800 5750) SIG_NAME M_L_CPU0_SA_DQS_DN<2>
J 0
(-5790 5760);
DISPLAY 0.659574 (-5790 5760);
PAINT MONO (-5790 5760);
DISPLAY INVISIBLE (-5790 5760);
FORCEPROP 1 LASTPIN (-5800 5750) BN 2
J 2
(-5788 5758);
DISPLAY 0.489362 (-5788 5758);
PAINT GREEN (-5788 5758);
FORCEPROP 2 LAST CDS_LIB mstr_standard
J 2
(-5850 5750);
DISPLAY 0.723404 (-5850 5750);
PAINT MONO (-5850 5750);
DISPLAY INVISIBLE (-5850 5750);
FORCEPROP 1 LAST BODY_TYPE PLUMBING
J 2
(-5850 5800);
DISPLAY 0.872340 (-5850 5800);
PAINT GREEN (-5850 5800);
DISPLAY INVISIBLE (-5850 5800);
FORCEPROP 1 LAST HDL_TAP TRUE
J 2
(-6175 5625);
DISPLAY 0.872340 (-6175 5625);
DISPLAY INVISIBLE (-6175 5625);
FORCEPROP 1 LAST PATH I255
J 2
(-5848 5750);
DISPLAY 0.872340 (-5848 5750);
PAINT GREEN (-5848 5750);
DISPLAY INVISIBLE (-5848 5750);
FORCEADD TAP..1
R 2
(-5850 5650);
FORCEPROP 3 LASTPIN (-5800 5650) SIG_NAME M_L_CPU0_SA_DQS_DN<3>
J 0
(-5790 5660);
DISPLAY 0.659574 (-5790 5660);
PAINT MONO (-5790 5660);
DISPLAY INVISIBLE (-5790 5660);
FORCEPROP 1 LASTPIN (-5800 5650) BN 3
J 2
(-5788 5658);
DISPLAY 0.489362 (-5788 5658);
PAINT GREEN (-5788 5658);
FORCEPROP 2 LAST CDS_LIB mstr_standard
J 2
(-5850 5650);
DISPLAY 0.723404 (-5850 5650);
PAINT MONO (-5850 5650);
DISPLAY INVISIBLE (-5850 5650);
FORCEPROP 1 LAST BODY_TYPE PLUMBING
J 2
(-5850 5700);
DISPLAY 0.872340 (-5850 5700);
PAINT GREEN (-5850 5700);
DISPLAY INVISIBLE (-5850 5700);
FORCEPROP 1 LAST HDL_TAP TRUE
J 2
(-6175 5525);
DISPLAY 0.872340 (-6175 5525);
DISPLAY INVISIBLE (-6175 5525);
FORCEPROP 1 LAST PATH I256
J 2
(-5848 5650);
DISPLAY 0.872340 (-5848 5650);
PAINT GREEN (-5848 5650);
DISPLAY INVISIBLE (-5848 5650);
FORCEADD TAP..1
R 2
(-5850 5450);
FORCEPROP 3 LASTPIN (-5800 5450) SIG_NAME M_L_CPU0_SA_DQS_DN<5>
J 0
(-5790 5460);
DISPLAY 0.659574 (-5790 5460);
PAINT MONO (-5790 5460);
DISPLAY INVISIBLE (-5790 5460);
FORCEPROP 1 LASTPIN (-5800 5450) BN 5
J 2
(-5788 5458);
DISPLAY 0.489362 (-5788 5458);
PAINT GREEN (-5788 5458);
FORCEPROP 2 LAST CDS_LIB mstr_standard
J 2
(-5850 5450);
DISPLAY 0.723404 (-5850 5450);
PAINT MONO (-5850 5450);
DISPLAY INVISIBLE (-5850 5450);
FORCEPROP 1 LAST BODY_TYPE PLUMBING
J 2
(-5850 5500);
DISPLAY 0.872340 (-5850 5500);
PAINT GREEN (-5850 5500);
DISPLAY INVISIBLE (-5850 5500);
FORCEPROP 1 LAST HDL_TAP TRUE
J 2
(-6175 5325);
DISPLAY 0.872340 (-6175 5325);
DISPLAY INVISIBLE (-6175 5325);
FORCEPROP 1 LAST PATH I257
J 2
(-5848 5450);
DISPLAY 0.872340 (-5848 5450);
PAINT GREEN (-5848 5450);
DISPLAY INVISIBLE (-5848 5450);
FORCEADD TAP..1
R 2
(-5850 5550);
FORCEPROP 3 LASTPIN (-5800 5550) SIG_NAME M_L_CPU0_SA_DQS_DN<4>
J 0
(-5790 5560);
DISPLAY 0.659574 (-5790 5560);
PAINT MONO (-5790 5560);
DISPLAY INVISIBLE (-5790 5560);
FORCEPROP 1 LASTPIN (-5800 5550) BN 4
J 2
(-5788 5558);
DISPLAY 0.489362 (-5788 5558);
PAINT GREEN (-5788 5558);
FORCEPROP 2 LAST CDS_LIB mstr_standard
J 2
(-5850 5550);
DISPLAY 0.723404 (-5850 5550);
PAINT MONO (-5850 5550);
DISPLAY INVISIBLE (-5850 5550);
FORCEPROP 1 LAST BODY_TYPE PLUMBING
J 2
(-5850 5600);
DISPLAY 0.872340 (-5850 5600);
PAINT GREEN (-5850 5600);
DISPLAY INVISIBLE (-5850 5600);
FORCEPROP 1 LAST HDL_TAP TRUE
J 2
(-6175 5425);
DISPLAY 0.872340 (-6175 5425);
DISPLAY INVISIBLE (-6175 5425);
FORCEPROP 1 LAST PATH I258
J 2
(-5848 5550);
DISPLAY 0.872340 (-5848 5550);
PAINT GREEN (-5848 5550);
DISPLAY INVISIBLE (-5848 5550);
FORCEADD TAP..1
R 2
(-5850 5350);
FORCEPROP 3 LASTPIN (-5800 5350) SIG_NAME M_L_CPU0_SA_DQS_DN<6>
J 0
(-5790 5360);
DISPLAY 0.659574 (-5790 5360);
PAINT MONO (-5790 5360);
DISPLAY INVISIBLE (-5790 5360);
FORCEPROP 1 LASTPIN (-5800 5350) BN 6
J 2
(-5788 5358);
DISPLAY 0.489362 (-5788 5358);
PAINT GREEN (-5788 5358);
FORCEPROP 2 LAST CDS_LIB mstr_standard
J 2
(-5850 5350);
DISPLAY 0.723404 (-5850 5350);
PAINT MONO (-5850 5350);
DISPLAY INVISIBLE (-5850 5350);
FORCEPROP 1 LAST BODY_TYPE PLUMBING
J 2
(-5850 5400);
DISPLAY 0.872340 (-5850 5400);
PAINT GREEN (-5850 5400);
DISPLAY INVISIBLE (-5850 5400);
FORCEPROP 1 LAST HDL_TAP TRUE
J 2
(-6175 5225);
DISPLAY 0.872340 (-6175 5225);
DISPLAY INVISIBLE (-6175 5225);
FORCEPROP 1 LAST PATH I259
J 2
(-5848 5350);
DISPLAY 0.872340 (-5848 5350);
PAINT GREEN (-5848 5350);
DISPLAY INVISIBLE (-5848 5350);
FORCEADD TAP..1
R 2
(-5850 5250);
FORCEPROP 3 LASTPIN (-5800 5250) SIG_NAME M_L_CPU0_SA_DQS_DN<7>
J 0
(-5790 5260);
DISPLAY 0.659574 (-5790 5260);
PAINT MONO (-5790 5260);
DISPLAY INVISIBLE (-5790 5260);
FORCEPROP 1 LASTPIN (-5800 5250) BN 7
J 2
(-5788 5258);
DISPLAY 0.489362 (-5788 5258);
PAINT GREEN (-5788 5258);
FORCEPROP 2 LAST CDS_LIB mstr_standard
J 2
(-5850 5250);
DISPLAY 0.723404 (-5850 5250);
PAINT MONO (-5850 5250);
DISPLAY INVISIBLE (-5850 5250);
FORCEPROP 1 LAST BODY_TYPE PLUMBING
J 2
(-5850 5300);
DISPLAY 0.872340 (-5850 5300);
PAINT GREEN (-5850 5300);
DISPLAY INVISIBLE (-5850 5300);
FORCEPROP 1 LAST HDL_TAP TRUE
J 2
(-6175 5125);
DISPLAY 0.872340 (-6175 5125);
DISPLAY INVISIBLE (-6175 5125);
FORCEPROP 1 LAST PATH I260
J 2
(-5848 5250);
DISPLAY 0.872340 (-5848 5250);
PAINT GREEN (-5848 5250);
DISPLAY INVISIBLE (-5848 5250);
FORCEADD TAP..1
R 2
(-5850 5150);
FORCEPROP 3 LASTPIN (-5800 5150) SIG_NAME M_L_CPU0_SA_DQS_DN<8>
J 0
(-5790 5160);
DISPLAY 0.659574 (-5790 5160);
PAINT MONO (-5790 5160);
DISPLAY INVISIBLE (-5790 5160);
FORCEPROP 1 LASTPIN (-5800 5150) BN 8
J 2
(-5788 5158);
DISPLAY 0.489362 (-5788 5158);
PAINT GREEN (-5788 5158);
FORCEPROP 2 LAST CDS_LIB mstr_standard
J 2
(-5850 5150);
DISPLAY 0.723404 (-5850 5150);
PAINT MONO (-5850 5150);
DISPLAY INVISIBLE (-5850 5150);
FORCEPROP 1 LAST BODY_TYPE PLUMBING
J 2
(-5850 5200);
DISPLAY 0.872340 (-5850 5200);
PAINT GREEN (-5850 5200);
DISPLAY INVISIBLE (-5850 5200);
FORCEPROP 1 LAST HDL_TAP TRUE
J 2
(-6175 5025);
DISPLAY 0.872340 (-6175 5025);
DISPLAY INVISIBLE (-6175 5025);
FORCEPROP 1 LAST PATH I261
J 2
(-5848 5150);
DISPLAY 0.872340 (-5848 5150);
PAINT GREEN (-5848 5150);
DISPLAY INVISIBLE (-5848 5150);
FORCEADD TAP..1
R 2
(-5650 5100);
FORCEPROP 3 LASTPIN (-5600 5100) SIG_NAME M_L_CPU0_SA_DQS_DP<9>
J 0
(-5590 5110);
DISPLAY 0.659574 (-5590 5110);
PAINT MONO (-5590 5110);
DISPLAY INVISIBLE (-5590 5110);
FORCEPROP 1 LASTPIN (-5600 5100) BN 9
J 2
(-5588 5108);
DISPLAY 0.489362 (-5588 5108);
PAINT GREEN (-5588 5108);
FORCEPROP 2 LAST CDS_LIB mstr_standard
J 2
(-5650 5100);
DISPLAY 0.723404 (-5650 5100);
PAINT MONO (-5650 5100);
DISPLAY INVISIBLE (-5650 5100);
FORCEPROP 1 LAST BODY_TYPE PLUMBING
J 2
(-5650 5150);
DISPLAY 0.872340 (-5650 5150);
PAINT GREEN (-5650 5150);
DISPLAY INVISIBLE (-5650 5150);
FORCEPROP 1 LAST HDL_TAP TRUE
J 2
(-5975 4975);
DISPLAY 0.872340 (-5975 4975);
DISPLAY INVISIBLE (-5975 4975);
FORCEPROP 1 LAST PATH I262
J 2
(-5648 5100);
DISPLAY 0.872340 (-5648 5100);
PAINT GREEN (-5648 5100);
DISPLAY INVISIBLE (-5648 5100);
FORCEADD TAP..1
R 2
(-5650 4950);
FORCEPROP 3 LASTPIN (-5600 4950) SIG_NAME M_L_CPU0_SB_DQS_DP<0>
J 0
(-5590 4960);
DISPLAY 0.659574 (-5590 4960);
PAINT MONO (-5590 4960);
DISPLAY INVISIBLE (-5590 4960);
FORCEPROP 1 LASTPIN (-5600 4950) BN 0
J 2
(-5588 4958);
DISPLAY 0.489362 (-5588 4958);
PAINT GREEN (-5588 4958);
FORCEPROP 2 LAST CDS_LIB mstr_standard
J 2
(-5650 4950);
DISPLAY 0.723404 (-5650 4950);
PAINT MONO (-5650 4950);
DISPLAY INVISIBLE (-5650 4950);
FORCEPROP 1 LAST BODY_TYPE PLUMBING
J 2
(-5650 5000);
DISPLAY 0.872340 (-5650 5000);
PAINT GREEN (-5650 5000);
DISPLAY INVISIBLE (-5650 5000);
FORCEPROP 1 LAST HDL_TAP TRUE
J 2
(-5975 4825);
DISPLAY 0.872340 (-5975 4825);
DISPLAY INVISIBLE (-5975 4825);
FORCEPROP 1 LAST PATH I263
J 2
(-5648 4950);
DISPLAY 0.872340 (-5648 4950);
PAINT GREEN (-5648 4950);
DISPLAY INVISIBLE (-5648 4950);
FORCEADD TAP..1
R 2
(-5650 4850);
FORCEPROP 3 LASTPIN (-5600 4850) SIG_NAME M_L_CPU0_SB_DQS_DP<1>
J 0
(-5590 4860);
DISPLAY 0.659574 (-5590 4860);
PAINT MONO (-5590 4860);
DISPLAY INVISIBLE (-5590 4860);
FORCEPROP 1 LASTPIN (-5600 4850) BN 1
J 2
(-5588 4858);
DISPLAY 0.489362 (-5588 4858);
PAINT GREEN (-5588 4858);
FORCEPROP 2 LAST CDS_LIB mstr_standard
J 2
(-5650 4850);
DISPLAY 0.723404 (-5650 4850);
PAINT MONO (-5650 4850);
DISPLAY INVISIBLE (-5650 4850);
FORCEPROP 1 LAST BODY_TYPE PLUMBING
J 2
(-5650 4900);
DISPLAY 0.872340 (-5650 4900);
PAINT GREEN (-5650 4900);
DISPLAY INVISIBLE (-5650 4900);
FORCEPROP 1 LAST HDL_TAP TRUE
J 2
(-5975 4725);
DISPLAY 0.872340 (-5975 4725);
DISPLAY INVISIBLE (-5975 4725);
FORCEPROP 1 LAST PATH I264
J 2
(-5648 4850);
DISPLAY 0.872340 (-5648 4850);
PAINT GREEN (-5648 4850);
DISPLAY INVISIBLE (-5648 4850);
FORCEADD TAP..1
R 2
(-5650 4750);
FORCEPROP 3 LASTPIN (-5600 4750) SIG_NAME M_L_CPU0_SB_DQS_DP<2>
J 0
(-5590 4760);
DISPLAY 0.659574 (-5590 4760);
PAINT MONO (-5590 4760);
DISPLAY INVISIBLE (-5590 4760);
FORCEPROP 1 LASTPIN (-5600 4750) BN 2
J 2
(-5588 4758);
DISPLAY 0.489362 (-5588 4758);
PAINT GREEN (-5588 4758);
FORCEPROP 2 LAST CDS_LIB mstr_standard
J 2
(-5650 4750);
DISPLAY 0.723404 (-5650 4750);
PAINT MONO (-5650 4750);
DISPLAY INVISIBLE (-5650 4750);
FORCEPROP 1 LAST BODY_TYPE PLUMBING
J 2
(-5650 4800);
DISPLAY 0.872340 (-5650 4800);
PAINT GREEN (-5650 4800);
DISPLAY INVISIBLE (-5650 4800);
FORCEPROP 1 LAST HDL_TAP TRUE
J 2
(-5975 4625);
DISPLAY 0.872340 (-5975 4625);
DISPLAY INVISIBLE (-5975 4625);
FORCEPROP 1 LAST PATH I265
J 2
(-5648 4750);
DISPLAY 0.872340 (-5648 4750);
PAINT GREEN (-5648 4750);
DISPLAY INVISIBLE (-5648 4750);
FORCEADD TAP..1
R 2
(-5650 4650);
FORCEPROP 3 LASTPIN (-5600 4650) SIG_NAME M_L_CPU0_SB_DQS_DP<3>
J 0
(-5590 4660);
DISPLAY 0.659574 (-5590 4660);
PAINT MONO (-5590 4660);
DISPLAY INVISIBLE (-5590 4660);
FORCEPROP 1 LASTPIN (-5600 4650) BN 3
J 2
(-5588 4658);
DISPLAY 0.489362 (-5588 4658);
PAINT GREEN (-5588 4658);
FORCEPROP 2 LAST CDS_LIB mstr_standard
J 2
(-5650 4650);
DISPLAY 0.723404 (-5650 4650);
PAINT MONO (-5650 4650);
DISPLAY INVISIBLE (-5650 4650);
FORCEPROP 1 LAST BODY_TYPE PLUMBING
J 2
(-5650 4700);
DISPLAY 0.872340 (-5650 4700);
PAINT GREEN (-5650 4700);
DISPLAY INVISIBLE (-5650 4700);
FORCEPROP 1 LAST HDL_TAP TRUE
J 2
(-5975 4525);
DISPLAY 0.872340 (-5975 4525);
DISPLAY INVISIBLE (-5975 4525);
FORCEPROP 1 LAST PATH I266
J 2
(-5648 4650);
DISPLAY 0.872340 (-5648 4650);
PAINT GREEN (-5648 4650);
DISPLAY INVISIBLE (-5648 4650);
FORCEADD TAP..1
R 2
(-5650 4550);
FORCEPROP 3 LASTPIN (-5600 4550) SIG_NAME M_L_CPU0_SB_DQS_DP<4>
J 0
(-5590 4560);
DISPLAY 0.659574 (-5590 4560);
PAINT MONO (-5590 4560);
DISPLAY INVISIBLE (-5590 4560);
FORCEPROP 1 LASTPIN (-5600 4550) BN 4
J 2
(-5588 4558);
DISPLAY 0.489362 (-5588 4558);
PAINT GREEN (-5588 4558);
FORCEPROP 2 LAST CDS_LIB mstr_standard
J 2
(-5650 4550);
DISPLAY 0.723404 (-5650 4550);
PAINT MONO (-5650 4550);
DISPLAY INVISIBLE (-5650 4550);
FORCEPROP 1 LAST BODY_TYPE PLUMBING
J 2
(-5650 4600);
DISPLAY 0.872340 (-5650 4600);
PAINT GREEN (-5650 4600);
DISPLAY INVISIBLE (-5650 4600);
FORCEPROP 1 LAST HDL_TAP TRUE
J 2
(-5975 4425);
DISPLAY 0.872340 (-5975 4425);
DISPLAY INVISIBLE (-5975 4425);
FORCEPROP 1 LAST PATH I267
J 2
(-5648 4550);
DISPLAY 0.872340 (-5648 4550);
PAINT GREEN (-5648 4550);
DISPLAY INVISIBLE (-5648 4550);
FORCEADD TAP..1
R 2
(-5650 4450);
FORCEPROP 3 LASTPIN (-5600 4450) SIG_NAME M_L_CPU0_SB_DQS_DP<5>
J 0
(-5590 4460);
DISPLAY 0.659574 (-5590 4460);
PAINT MONO (-5590 4460);
DISPLAY INVISIBLE (-5590 4460);
FORCEPROP 1 LASTPIN (-5600 4450) BN 5
J 2
(-5588 4458);
DISPLAY 0.489362 (-5588 4458);
PAINT GREEN (-5588 4458);
FORCEPROP 2 LAST CDS_LIB mstr_standard
J 2
(-5650 4450);
DISPLAY 0.723404 (-5650 4450);
PAINT MONO (-5650 4450);
DISPLAY INVISIBLE (-5650 4450);
FORCEPROP 1 LAST BODY_TYPE PLUMBING
J 2
(-5650 4500);
DISPLAY 0.872340 (-5650 4500);
PAINT GREEN (-5650 4500);
DISPLAY INVISIBLE (-5650 4500);
FORCEPROP 1 LAST HDL_TAP TRUE
J 2
(-5975 4325);
DISPLAY 0.872340 (-5975 4325);
DISPLAY INVISIBLE (-5975 4325);
FORCEPROP 1 LAST PATH I268
J 2
(-5648 4450);
DISPLAY 0.872340 (-5648 4450);
PAINT GREEN (-5648 4450);
DISPLAY INVISIBLE (-5648 4450);
FORCEADD TAP..1
R 2
(-5650 4350);
FORCEPROP 3 LASTPIN (-5600 4350) SIG_NAME M_L_CPU0_SB_DQS_DP<6>
J 0
(-5590 4360);
DISPLAY 0.659574 (-5590 4360);
PAINT MONO (-5590 4360);
DISPLAY INVISIBLE (-5590 4360);
FORCEPROP 1 LASTPIN (-5600 4350) BN 6
J 2
(-5588 4358);
DISPLAY 0.489362 (-5588 4358);
PAINT GREEN (-5588 4358);
FORCEPROP 2 LAST CDS_LIB mstr_standard
J 2
(-5650 4350);
DISPLAY 0.723404 (-5650 4350);
PAINT MONO (-5650 4350);
DISPLAY INVISIBLE (-5650 4350);
FORCEPROP 1 LAST BODY_TYPE PLUMBING
J 2
(-5650 4400);
DISPLAY 0.872340 (-5650 4400);
PAINT GREEN (-5650 4400);
DISPLAY INVISIBLE (-5650 4400);
FORCEPROP 1 LAST HDL_TAP TRUE
J 2
(-5975 4225);
DISPLAY 0.872340 (-5975 4225);
DISPLAY INVISIBLE (-5975 4225);
FORCEPROP 1 LAST PATH I269
J 2
(-5648 4350);
DISPLAY 0.872340 (-5648 4350);
PAINT GREEN (-5648 4350);
DISPLAY INVISIBLE (-5648 4350);
FORCEADD TAP..1
R 2
(-5650 4250);
FORCEPROP 3 LASTPIN (-5600 4250) SIG_NAME M_L_CPU0_SB_DQS_DP<7>
J 0
(-5590 4260);
DISPLAY 0.659574 (-5590 4260);
PAINT MONO (-5590 4260);
DISPLAY INVISIBLE (-5590 4260);
FORCEPROP 1 LASTPIN (-5600 4250) BN 7
J 2
(-5588 4258);
DISPLAY 0.489362 (-5588 4258);
PAINT GREEN (-5588 4258);
FORCEPROP 2 LAST CDS_LIB mstr_standard
J 2
(-5650 4250);
DISPLAY 0.723404 (-5650 4250);
PAINT MONO (-5650 4250);
DISPLAY INVISIBLE (-5650 4250);
FORCEPROP 1 LAST BODY_TYPE PLUMBING
J 2
(-5650 4300);
DISPLAY 0.872340 (-5650 4300);
PAINT GREEN (-5650 4300);
DISPLAY INVISIBLE (-5650 4300);
FORCEPROP 1 LAST HDL_TAP TRUE
J 2
(-5975 4125);
DISPLAY 0.872340 (-5975 4125);
DISPLAY INVISIBLE (-5975 4125);
FORCEPROP 1 LAST PATH I270
J 2
(-5648 4250);
DISPLAY 0.872340 (-5648 4250);
PAINT GREEN (-5648 4250);
DISPLAY INVISIBLE (-5648 4250);
FORCEADD TAP..1
R 2
(-5650 4150);
FORCEPROP 3 LASTPIN (-5600 4150) SIG_NAME M_L_CPU0_SB_DQS_DP<8>
J 0
(-5590 4160);
DISPLAY 0.659574 (-5590 4160);
PAINT MONO (-5590 4160);
DISPLAY INVISIBLE (-5590 4160);
FORCEPROP 1 LASTPIN (-5600 4150) BN 8
J 2
(-5588 4158);
DISPLAY 0.489362 (-5588 4158);
PAINT GREEN (-5588 4158);
FORCEPROP 2 LAST CDS_LIB mstr_standard
J 2
(-5650 4150);
DISPLAY 0.723404 (-5650 4150);
PAINT MONO (-5650 4150);
DISPLAY INVISIBLE (-5650 4150);
FORCEPROP 1 LAST BODY_TYPE PLUMBING
J 2
(-5650 4200);
DISPLAY 0.872340 (-5650 4200);
PAINT GREEN (-5650 4200);
DISPLAY INVISIBLE (-5650 4200);
FORCEPROP 1 LAST HDL_TAP TRUE
J 2
(-5975 4025);
DISPLAY 0.872340 (-5975 4025);
DISPLAY INVISIBLE (-5975 4025);
FORCEPROP 1 LAST PATH I271
J 2
(-5648 4150);
DISPLAY 0.872340 (-5648 4150);
PAINT GREEN (-5648 4150);
DISPLAY INVISIBLE (-5648 4150);
FORCEADD TAP..1
R 2
(-5850 4900);
FORCEPROP 3 LASTPIN (-5800 4900) SIG_NAME M_L_CPU0_SB_DQS_DN<0>
J 0
(-5790 4910);
DISPLAY 0.659574 (-5790 4910);
PAINT MONO (-5790 4910);
DISPLAY INVISIBLE (-5790 4910);
FORCEPROP 1 LASTPIN (-5800 4900) BN 0
J 2
(-5788 4908);
DISPLAY 0.489362 (-5788 4908);
PAINT GREEN (-5788 4908);
FORCEPROP 2 LAST CDS_LIB mstr_standard
J 2
(-5850 4900);
DISPLAY 0.723404 (-5850 4900);
PAINT MONO (-5850 4900);
DISPLAY INVISIBLE (-5850 4900);
FORCEPROP 1 LAST BODY_TYPE PLUMBING
J 2
(-5850 4950);
DISPLAY 0.872340 (-5850 4950);
PAINT GREEN (-5850 4950);
DISPLAY INVISIBLE (-5850 4950);
FORCEPROP 1 LAST HDL_TAP TRUE
J 2
(-6175 4775);
DISPLAY 0.872340 (-6175 4775);
DISPLAY INVISIBLE (-6175 4775);
FORCEPROP 1 LAST PATH I272
J 2
(-5848 4900);
DISPLAY 0.872340 (-5848 4900);
PAINT GREEN (-5848 4900);
DISPLAY INVISIBLE (-5848 4900);
FORCEADD TAP..1
R 2
(-5850 5050);
FORCEPROP 3 LASTPIN (-5800 5050) SIG_NAME M_L_CPU0_SA_DQS_DN<9>
J 0
(-5790 5060);
DISPLAY 0.659574 (-5790 5060);
PAINT MONO (-5790 5060);
DISPLAY INVISIBLE (-5790 5060);
FORCEPROP 1 LASTPIN (-5800 5050) BN 9
J 2
(-5788 5058);
DISPLAY 0.489362 (-5788 5058);
PAINT GREEN (-5788 5058);
FORCEPROP 2 LAST CDS_LIB mstr_standard
J 2
(-5850 5050);
DISPLAY 0.723404 (-5850 5050);
PAINT MONO (-5850 5050);
DISPLAY INVISIBLE (-5850 5050);
FORCEPROP 1 LAST BODY_TYPE PLUMBING
J 2
(-5850 5100);
DISPLAY 0.872340 (-5850 5100);
PAINT GREEN (-5850 5100);
DISPLAY INVISIBLE (-5850 5100);
FORCEPROP 1 LAST HDL_TAP TRUE
J 2
(-6175 4925);
DISPLAY 0.872340 (-6175 4925);
DISPLAY INVISIBLE (-6175 4925);
FORCEPROP 1 LAST PATH I273
J 2
(-5848 5050);
DISPLAY 0.872340 (-5848 5050);
PAINT GREEN (-5848 5050);
DISPLAY INVISIBLE (-5848 5050);
FORCEADD TAP..1
R 2
(-5850 4800);
FORCEPROP 3 LASTPIN (-5800 4800) SIG_NAME M_L_CPU0_SB_DQS_DN<1>
J 0
(-5790 4810);
DISPLAY 0.659574 (-5790 4810);
PAINT MONO (-5790 4810);
DISPLAY INVISIBLE (-5790 4810);
FORCEPROP 1 LASTPIN (-5800 4800) BN 1
J 2
(-5788 4808);
DISPLAY 0.489362 (-5788 4808);
PAINT GREEN (-5788 4808);
FORCEPROP 2 LAST CDS_LIB mstr_standard
J 2
(-5850 4800);
DISPLAY 0.723404 (-5850 4800);
PAINT MONO (-5850 4800);
DISPLAY INVISIBLE (-5850 4800);
FORCEPROP 1 LAST BODY_TYPE PLUMBING
J 2
(-5850 4850);
DISPLAY 0.872340 (-5850 4850);
PAINT GREEN (-5850 4850);
DISPLAY INVISIBLE (-5850 4850);
FORCEPROP 1 LAST HDL_TAP TRUE
J 2
(-6175 4675);
DISPLAY 0.872340 (-6175 4675);
DISPLAY INVISIBLE (-6175 4675);
FORCEPROP 1 LAST PATH I274
J 2
(-5848 4800);
DISPLAY 0.872340 (-5848 4800);
PAINT GREEN (-5848 4800);
DISPLAY INVISIBLE (-5848 4800);
FORCEADD TAP..1
R 2
(-5850 4700);
FORCEPROP 3 LASTPIN (-5800 4700) SIG_NAME M_L_CPU0_SB_DQS_DN<2>
J 0
(-5790 4710);
DISPLAY 0.659574 (-5790 4710);
PAINT MONO (-5790 4710);
DISPLAY INVISIBLE (-5790 4710);
FORCEPROP 1 LASTPIN (-5800 4700) BN 2
J 2
(-5788 4708);
DISPLAY 0.489362 (-5788 4708);
PAINT GREEN (-5788 4708);
FORCEPROP 2 LAST CDS_LIB mstr_standard
J 2
(-5850 4700);
DISPLAY 0.723404 (-5850 4700);
PAINT MONO (-5850 4700);
DISPLAY INVISIBLE (-5850 4700);
FORCEPROP 1 LAST BODY_TYPE PLUMBING
J 2
(-5850 4750);
DISPLAY 0.872340 (-5850 4750);
PAINT GREEN (-5850 4750);
DISPLAY INVISIBLE (-5850 4750);
FORCEPROP 1 LAST HDL_TAP TRUE
J 2
(-6175 4575);
DISPLAY 0.872340 (-6175 4575);
DISPLAY INVISIBLE (-6175 4575);
FORCEPROP 1 LAST PATH I275
J 2
(-5848 4700);
DISPLAY 0.872340 (-5848 4700);
PAINT GREEN (-5848 4700);
DISPLAY INVISIBLE (-5848 4700);
FORCEADD TAP..1
R 2
(-5850 4600);
FORCEPROP 3 LASTPIN (-5800 4600) SIG_NAME M_L_CPU0_SB_DQS_DN<3>
J 0
(-5790 4610);
DISPLAY 0.659574 (-5790 4610);
PAINT MONO (-5790 4610);
DISPLAY INVISIBLE (-5790 4610);
FORCEPROP 1 LASTPIN (-5800 4600) BN 3
J 2
(-5788 4608);
DISPLAY 0.489362 (-5788 4608);
PAINT GREEN (-5788 4608);
FORCEPROP 2 LAST CDS_LIB mstr_standard
J 2
(-5850 4600);
DISPLAY 0.723404 (-5850 4600);
PAINT MONO (-5850 4600);
DISPLAY INVISIBLE (-5850 4600);
FORCEPROP 1 LAST BODY_TYPE PLUMBING
J 2
(-5850 4650);
DISPLAY 0.872340 (-5850 4650);
PAINT GREEN (-5850 4650);
DISPLAY INVISIBLE (-5850 4650);
FORCEPROP 1 LAST HDL_TAP TRUE
J 2
(-6175 4475);
DISPLAY 0.872340 (-6175 4475);
DISPLAY INVISIBLE (-6175 4475);
FORCEPROP 1 LAST PATH I276
J 2
(-5848 4600);
DISPLAY 0.872340 (-5848 4600);
PAINT GREEN (-5848 4600);
DISPLAY INVISIBLE (-5848 4600);
FORCEADD TAP..1
R 2
(-5850 4500);
FORCEPROP 3 LASTPIN (-5800 4500) SIG_NAME M_L_CPU0_SB_DQS_DN<4>
J 0
(-5790 4510);
DISPLAY 0.659574 (-5790 4510);
PAINT MONO (-5790 4510);
DISPLAY INVISIBLE (-5790 4510);
FORCEPROP 1 LASTPIN (-5800 4500) BN 4
J 2
(-5788 4508);
DISPLAY 0.489362 (-5788 4508);
PAINT GREEN (-5788 4508);
FORCEPROP 2 LAST CDS_LIB mstr_standard
J 2
(-5850 4500);
DISPLAY 0.723404 (-5850 4500);
PAINT MONO (-5850 4500);
DISPLAY INVISIBLE (-5850 4500);
FORCEPROP 1 LAST BODY_TYPE PLUMBING
J 2
(-5850 4550);
DISPLAY 0.872340 (-5850 4550);
PAINT GREEN (-5850 4550);
DISPLAY INVISIBLE (-5850 4550);
FORCEPROP 1 LAST HDL_TAP TRUE
J 2
(-6175 4375);
DISPLAY 0.872340 (-6175 4375);
DISPLAY INVISIBLE (-6175 4375);
FORCEPROP 1 LAST PATH I277
J 2
(-5848 4500);
DISPLAY 0.872340 (-5848 4500);
PAINT GREEN (-5848 4500);
DISPLAY INVISIBLE (-5848 4500);
FORCEADD TAP..1
R 2
(-5850 4400);
FORCEPROP 3 LASTPIN (-5800 4400) SIG_NAME M_L_CPU0_SB_DQS_DN<5>
J 0
(-5790 4410);
DISPLAY 0.659574 (-5790 4410);
PAINT MONO (-5790 4410);
DISPLAY INVISIBLE (-5790 4410);
FORCEPROP 1 LASTPIN (-5800 4400) BN 5
J 2
(-5788 4408);
DISPLAY 0.489362 (-5788 4408);
PAINT GREEN (-5788 4408);
FORCEPROP 2 LAST CDS_LIB mstr_standard
J 2
(-5850 4400);
DISPLAY 0.723404 (-5850 4400);
PAINT MONO (-5850 4400);
DISPLAY INVISIBLE (-5850 4400);
FORCEPROP 1 LAST BODY_TYPE PLUMBING
J 2
(-5850 4450);
DISPLAY 0.872340 (-5850 4450);
PAINT GREEN (-5850 4450);
DISPLAY INVISIBLE (-5850 4450);
FORCEPROP 1 LAST HDL_TAP TRUE
J 2
(-6175 4275);
DISPLAY 0.872340 (-6175 4275);
DISPLAY INVISIBLE (-6175 4275);
FORCEPROP 1 LAST PATH I278
J 2
(-5848 4400);
DISPLAY 0.872340 (-5848 4400);
PAINT GREEN (-5848 4400);
DISPLAY INVISIBLE (-5848 4400);
FORCEADD TAP..1
R 2
(-5850 4300);
FORCEPROP 3 LASTPIN (-5800 4300) SIG_NAME M_L_CPU0_SB_DQS_DN<6>
J 0
(-5790 4310);
DISPLAY 0.659574 (-5790 4310);
PAINT MONO (-5790 4310);
DISPLAY INVISIBLE (-5790 4310);
FORCEPROP 1 LASTPIN (-5800 4300) BN 6
J 2
(-5788 4308);
DISPLAY 0.489362 (-5788 4308);
PAINT GREEN (-5788 4308);
FORCEPROP 2 LAST CDS_LIB mstr_standard
J 2
(-5850 4300);
DISPLAY 0.723404 (-5850 4300);
PAINT MONO (-5850 4300);
DISPLAY INVISIBLE (-5850 4300);
FORCEPROP 1 LAST BODY_TYPE PLUMBING
J 2
(-5850 4350);
DISPLAY 0.872340 (-5850 4350);
PAINT GREEN (-5850 4350);
DISPLAY INVISIBLE (-5850 4350);
FORCEPROP 1 LAST HDL_TAP TRUE
J 2
(-6175 4175);
DISPLAY 0.872340 (-6175 4175);
DISPLAY INVISIBLE (-6175 4175);
FORCEPROP 1 LAST PATH I279
J 2
(-5848 4300);
DISPLAY 0.872340 (-5848 4300);
PAINT GREEN (-5848 4300);
DISPLAY INVISIBLE (-5848 4300);
FORCEADD TAP..1
R 2
(-5850 4200);
FORCEPROP 3 LASTPIN (-5800 4200) SIG_NAME M_L_CPU0_SB_DQS_DN<7>
J 0
(-5790 4210);
DISPLAY 0.659574 (-5790 4210);
PAINT MONO (-5790 4210);
DISPLAY INVISIBLE (-5790 4210);
FORCEPROP 1 LASTPIN (-5800 4200) BN 7
J 2
(-5788 4208);
DISPLAY 0.489362 (-5788 4208);
PAINT GREEN (-5788 4208);
FORCEPROP 2 LAST CDS_LIB mstr_standard
J 2
(-5850 4200);
DISPLAY 0.723404 (-5850 4200);
PAINT MONO (-5850 4200);
DISPLAY INVISIBLE (-5850 4200);
FORCEPROP 1 LAST BODY_TYPE PLUMBING
J 2
(-5850 4250);
DISPLAY 0.872340 (-5850 4250);
PAINT GREEN (-5850 4250);
DISPLAY INVISIBLE (-5850 4250);
FORCEPROP 1 LAST HDL_TAP TRUE
J 2
(-6175 4075);
DISPLAY 0.872340 (-6175 4075);
DISPLAY INVISIBLE (-6175 4075);
FORCEPROP 1 LAST PATH I280
J 2
(-5848 4200);
DISPLAY 0.872340 (-5848 4200);
PAINT GREEN (-5848 4200);
DISPLAY INVISIBLE (-5848 4200);
FORCEADD TAP..1
R 2
(-5850 4100);
FORCEPROP 3 LASTPIN (-5800 4100) SIG_NAME M_L_CPU0_SB_DQS_DN<8>
J 0
(-5790 4110);
DISPLAY 0.659574 (-5790 4110);
PAINT MONO (-5790 4110);
DISPLAY INVISIBLE (-5790 4110);
FORCEPROP 1 LASTPIN (-5800 4100) BN 8
J 2
(-5788 4108);
DISPLAY 0.489362 (-5788 4108);
PAINT GREEN (-5788 4108);
FORCEPROP 2 LAST CDS_LIB mstr_standard
J 2
(-5850 4100);
DISPLAY 0.723404 (-5850 4100);
PAINT MONO (-5850 4100);
DISPLAY INVISIBLE (-5850 4100);
FORCEPROP 1 LAST BODY_TYPE PLUMBING
J 2
(-5850 4150);
DISPLAY 0.872340 (-5850 4150);
PAINT GREEN (-5850 4150);
DISPLAY INVISIBLE (-5850 4150);
FORCEPROP 1 LAST HDL_TAP TRUE
J 2
(-6175 3975);
DISPLAY 0.872340 (-6175 3975);
DISPLAY INVISIBLE (-6175 3975);
FORCEPROP 1 LAST PATH I281
J 2
(-5848 4100);
DISPLAY 0.872340 (-5848 4100);
PAINT GREEN (-5848 4100);
DISPLAY INVISIBLE (-5848 4100);
FORCEADD OFFPAGE..3
R 2
(-6550 6025);
FORCEPROP 2 LAST $XR0 97 
J 0
(-6799 6025);
DISPLAY 0.638298 (-6799 6025);
PAINT MONO (-6799 6025);
FORCEPROP 2 LAST CDS_LIB standard
J 0
(-6550 6025);
DISPLAY INVISIBLE (-6550 6025);
FORCEPROP 1 LAST OFFPAGE TRUE
J 2
(-6875 5900);
DISPLAY 0.872340 (-6875 5900);
PAINT GREEN (-6875 5900);
DISPLAY INVISIBLE (-6875 5900);
FORCEPROP 1 LAST COMMENT_BODY TRUE
J 2
(-6500 5925);
DISPLAY 0.872340 (-6500 5925);
PAINT GREEN (-6500 5925);
DISPLAY INVISIBLE (-6500 5925);
FORCEPROP 2 LAST PATH I282
J 0
(-6825 6075);
DISPLAY 1.021277 (-6825 6075);
DISPLAY INVISIBLE (-6825 6075);
FORCEADD OFFPAGE..3
R 2
(-6550 5975);
FORCEPROP 2 LAST $XR0 97 
J 0
(-6799 5975);
DISPLAY 0.638298 (-6799 5975);
PAINT MONO (-6799 5975);
FORCEPROP 2 LAST CDS_LIB standard
J 0
(-6550 5975);
DISPLAY INVISIBLE (-6550 5975);
FORCEPROP 1 LAST OFFPAGE TRUE
J 2
(-6875 5850);
DISPLAY 0.872340 (-6875 5850);
PAINT GREEN (-6875 5850);
DISPLAY INVISIBLE (-6875 5850);
FORCEPROP 1 LAST COMMENT_BODY TRUE
J 2
(-6500 5875);
DISPLAY 0.872340 (-6500 5875);
PAINT GREEN (-6500 5875);
DISPLAY INVISIBLE (-6500 5875);
FORCEPROP 2 LAST PATH I283
J 0
(-6825 6025);
DISPLAY 1.021277 (-6825 6025);
DISPLAY INVISIBLE (-6825 6025);
FORCEADD OFFPAGE..3
R 2
(-6550 4925);
FORCEPROP 2 LAST $XR0 97 
J 0
(-6799 4925);
DISPLAY 0.638298 (-6799 4925);
PAINT MONO (-6799 4925);
FORCEPROP 2 LAST CDS_LIB standard
J 0
(-6550 4925);
DISPLAY INVISIBLE (-6550 4925);
FORCEPROP 1 LAST OFFPAGE TRUE
J 2
(-6875 4800);
DISPLAY 0.872340 (-6875 4800);
PAINT GREEN (-6875 4800);
DISPLAY INVISIBLE (-6875 4800);
FORCEPROP 1 LAST COMMENT_BODY TRUE
J 2
(-6500 4825);
DISPLAY 0.872340 (-6500 4825);
PAINT GREEN (-6500 4825);
DISPLAY INVISIBLE (-6500 4825);
FORCEPROP 2 LAST PATH I284
J 0
(-6825 4975);
DISPLAY 1.021277 (-6825 4975);
DISPLAY INVISIBLE (-6825 4975);
FORCEADD OFFPAGE..3
R 2
(-6550 4975);
FORCEPROP 2 LAST $XR0 97 
J 0
(-6799 4975);
DISPLAY 0.638298 (-6799 4975);
PAINT MONO (-6799 4975);
FORCEPROP 2 LAST CDS_LIB standard
J 0
(-6550 4975);
DISPLAY INVISIBLE (-6550 4975);
FORCEPROP 1 LAST OFFPAGE TRUE
J 2
(-6875 4850);
DISPLAY 0.872340 (-6875 4850);
PAINT GREEN (-6875 4850);
DISPLAY INVISIBLE (-6875 4850);
FORCEPROP 1 LAST COMMENT_BODY TRUE
J 2
(-6500 4875);
DISPLAY 0.872340 (-6500 4875);
PAINT GREEN (-6500 4875);
DISPLAY INVISIBLE (-6500 4875);
FORCEPROP 2 LAST PATH I285
J 0
(-6825 5025);
DISPLAY 1.021277 (-6825 5025);
DISPLAY INVISIBLE (-6825 5025);
FORCEADD TAP..1
R 2
(-5650 4050);
FORCEPROP 3 LASTPIN (-5600 4050) SIG_NAME M_L_CPU0_SB_DQS_DP<9>
J 0
(-5590 4060);
DISPLAY 0.659574 (-5590 4060);
PAINT MONO (-5590 4060);
DISPLAY INVISIBLE (-5590 4060);
FORCEPROP 1 LASTPIN (-5600 4050) BN 9
J 2
(-5588 4058);
DISPLAY 0.489362 (-5588 4058);
PAINT GREEN (-5588 4058);
FORCEPROP 2 LAST CDS_LIB mstr_standard
J 2
(-5650 4050);
DISPLAY 0.723404 (-5650 4050);
PAINT MONO (-5650 4050);
DISPLAY INVISIBLE (-5650 4050);
FORCEPROP 1 LAST BODY_TYPE PLUMBING
J 2
(-5650 4100);
DISPLAY 0.872340 (-5650 4100);
PAINT GREEN (-5650 4100);
DISPLAY INVISIBLE (-5650 4100);
FORCEPROP 1 LAST HDL_TAP TRUE
J 2
(-5975 3925);
DISPLAY 0.872340 (-5975 3925);
DISPLAY INVISIBLE (-5975 3925);
FORCEPROP 1 LAST PATH I286
J 2
(-5648 4050);
DISPLAY 0.872340 (-5648 4050);
PAINT GREEN (-5648 4050);
DISPLAY INVISIBLE (-5648 4050);
FORCEADD TAP..1
R 2
(-5850 4000);
FORCEPROP 3 LASTPIN (-5800 4000) SIG_NAME M_L_CPU0_SB_DQS_DN<9>
J 0
(-5790 4010);
DISPLAY 0.659574 (-5790 4010);
PAINT MONO (-5790 4010);
DISPLAY INVISIBLE (-5790 4010);
FORCEPROP 1 LASTPIN (-5800 4000) BN 9
J 2
(-5788 4008);
DISPLAY 0.489362 (-5788 4008);
PAINT GREEN (-5788 4008);
FORCEPROP 2 LAST CDS_LIB mstr_standard
J 2
(-5850 4000);
DISPLAY 0.723404 (-5850 4000);
PAINT MONO (-5850 4000);
DISPLAY INVISIBLE (-5850 4000);
FORCEPROP 1 LAST BODY_TYPE PLUMBING
J 2
(-5850 4050);
DISPLAY 0.872340 (-5850 4050);
PAINT GREEN (-5850 4050);
DISPLAY INVISIBLE (-5850 4050);
FORCEPROP 1 LAST HDL_TAP TRUE
J 2
(-6175 3875);
DISPLAY 0.872340 (-6175 3875);
DISPLAY INVISIBLE (-6175 3875);
FORCEPROP 1 LAST PATH I287
J 2
(-5848 4000);
DISPLAY 0.872340 (-5848 4000);
PAINT GREEN (-5848 4000);
DISPLAY INVISIBLE (-5848 4000);
FORCEADD TAP..1
R 2
(-5850 3850);
FORCEPROP 3 LASTPIN (-5800 3850) SIG_NAME M_L_CPU0_SA_CA<0>
J 0
(-5790 3860);
DISPLAY 0.659574 (-5790 3860);
PAINT MONO (-5790 3860);
DISPLAY INVISIBLE (-5790 3860);
FORCEPROP 1 LASTPIN (-5800 3850) BN 0
J 2
(-5788 3858);
DISPLAY 0.489362 (-5788 3858);
PAINT GREEN (-5788 3858);
FORCEPROP 2 LAST CDS_LIB mstr_standard
J 0
(-5850 3850);
DISPLAY 0.723404 (-5850 3850);
PAINT MONO (-5850 3850);
DISPLAY INVISIBLE (-5850 3850);
FORCEPROP 1 LAST BODY_TYPE PLUMBING
J 2
(-5850 3900);
DISPLAY 0.872340 (-5850 3900);
PAINT GREEN (-5850 3900);
DISPLAY INVISIBLE (-5850 3900);
FORCEPROP 1 LAST HDL_TAP TRUE
J 2
(-6175 3725);
DISPLAY 0.872340 (-6175 3725);
DISPLAY INVISIBLE (-6175 3725);
FORCEPROP 1 LAST PATH I288
J 2
(-5848 3850);
DISPLAY 0.872340 (-5848 3850);
PAINT GREEN (-5848 3850);
DISPLAY INVISIBLE (-5848 3850);
FORCEADD TAP..1
R 2
(-5850 3750);
FORCEPROP 3 LASTPIN (-5800 3750) SIG_NAME M_L_CPU0_SA_CA<2>
J 0
(-5790 3760);
DISPLAY 0.659574 (-5790 3760);
PAINT MONO (-5790 3760);
DISPLAY INVISIBLE (-5790 3760);
FORCEPROP 1 LASTPIN (-5800 3750) BN 2
J 2
(-5788 3758);
DISPLAY 0.489362 (-5788 3758);
PAINT GREEN (-5788 3758);
FORCEPROP 2 LAST CDS_LIB mstr_standard
J 0
(-5850 3750);
DISPLAY 0.723404 (-5850 3750);
PAINT MONO (-5850 3750);
DISPLAY INVISIBLE (-5850 3750);
FORCEPROP 1 LAST BODY_TYPE PLUMBING
J 2
(-5850 3800);
DISPLAY 0.872340 (-5850 3800);
PAINT GREEN (-5850 3800);
DISPLAY INVISIBLE (-5850 3800);
FORCEPROP 1 LAST HDL_TAP TRUE
J 2
(-6175 3625);
DISPLAY 0.872340 (-6175 3625);
DISPLAY INVISIBLE (-6175 3625);
FORCEPROP 1 LAST PATH I289
J 2
(-5848 3750);
DISPLAY 0.872340 (-5848 3750);
PAINT GREEN (-5848 3750);
DISPLAY INVISIBLE (-5848 3750);
FORCEADD TAP..1
R 2
(-5850 3800);
FORCEPROP 3 LASTPIN (-5800 3800) SIG_NAME M_L_CPU0_SA_CA<1>
J 0
(-5790 3810);
DISPLAY 0.659574 (-5790 3810);
PAINT MONO (-5790 3810);
DISPLAY INVISIBLE (-5790 3810);
FORCEPROP 1 LASTPIN (-5800 3800) BN 1
J 2
(-5788 3808);
DISPLAY 0.489362 (-5788 3808);
PAINT GREEN (-5788 3808);
FORCEPROP 2 LAST CDS_LIB mstr_standard
J 0
(-5850 3800);
DISPLAY 0.723404 (-5850 3800);
PAINT MONO (-5850 3800);
DISPLAY INVISIBLE (-5850 3800);
FORCEPROP 1 LAST BODY_TYPE PLUMBING
J 2
(-5850 3850);
DISPLAY 0.872340 (-5850 3850);
PAINT GREEN (-5850 3850);
DISPLAY INVISIBLE (-5850 3850);
FORCEPROP 1 LAST HDL_TAP TRUE
J 2
(-6175 3675);
DISPLAY 0.872340 (-6175 3675);
DISPLAY INVISIBLE (-6175 3675);
FORCEPROP 1 LAST PATH I290
J 2
(-5848 3800);
DISPLAY 0.872340 (-5848 3800);
PAINT GREEN (-5848 3800);
DISPLAY INVISIBLE (-5848 3800);
FORCEADD TAP..1
R 2
(-5850 3700);
FORCEPROP 3 LASTPIN (-5800 3700) SIG_NAME M_L_CPU0_SA_CA<3>
J 0
(-5790 3710);
DISPLAY 0.659574 (-5790 3710);
PAINT MONO (-5790 3710);
DISPLAY INVISIBLE (-5790 3710);
FORCEPROP 1 LASTPIN (-5800 3700) BN 3
J 2
(-5788 3708);
DISPLAY 0.489362 (-5788 3708);
PAINT GREEN (-5788 3708);
FORCEPROP 2 LAST CDS_LIB mstr_standard
J 0
(-5850 3700);
DISPLAY 0.723404 (-5850 3700);
PAINT MONO (-5850 3700);
DISPLAY INVISIBLE (-5850 3700);
FORCEPROP 1 LAST BODY_TYPE PLUMBING
J 2
(-5850 3750);
DISPLAY 0.872340 (-5850 3750);
PAINT GREEN (-5850 3750);
DISPLAY INVISIBLE (-5850 3750);
FORCEPROP 1 LAST HDL_TAP TRUE
J 2
(-6175 3575);
DISPLAY 0.872340 (-6175 3575);
DISPLAY INVISIBLE (-6175 3575);
FORCEPROP 1 LAST PATH I291
J 2
(-5848 3700);
DISPLAY 0.872340 (-5848 3700);
PAINT GREEN (-5848 3700);
DISPLAY INVISIBLE (-5848 3700);
FORCEADD TAP..1
R 2
(-5850 3650);
FORCEPROP 3 LASTPIN (-5800 3650) SIG_NAME M_L_CPU0_SA_CA<4>
J 0
(-5790 3660);
DISPLAY 0.659574 (-5790 3660);
PAINT MONO (-5790 3660);
DISPLAY INVISIBLE (-5790 3660);
FORCEPROP 1 LASTPIN (-5800 3650) BN 4
J 2
(-5788 3658);
DISPLAY 0.489362 (-5788 3658);
PAINT GREEN (-5788 3658);
FORCEPROP 2 LAST CDS_LIB mstr_standard
J 0
(-5850 3650);
DISPLAY 0.723404 (-5850 3650);
PAINT MONO (-5850 3650);
DISPLAY INVISIBLE (-5850 3650);
FORCEPROP 1 LAST BODY_TYPE PLUMBING
J 2
(-5850 3700);
DISPLAY 0.872340 (-5850 3700);
PAINT GREEN (-5850 3700);
DISPLAY INVISIBLE (-5850 3700);
FORCEPROP 1 LAST HDL_TAP TRUE
J 2
(-6175 3525);
DISPLAY 0.872340 (-6175 3525);
DISPLAY INVISIBLE (-6175 3525);
FORCEPROP 1 LAST PATH I292
J 2
(-5848 3650);
DISPLAY 0.872340 (-5848 3650);
PAINT GREEN (-5848 3650);
DISPLAY INVISIBLE (-5848 3650);
FORCEADD TAP..1
R 2
(-5850 3600);
FORCEPROP 3 LASTPIN (-5800 3600) SIG_NAME M_L_CPU0_SA_CA<5>
J 0
(-5790 3610);
DISPLAY 0.659574 (-5790 3610);
PAINT MONO (-5790 3610);
DISPLAY INVISIBLE (-5790 3610);
FORCEPROP 1 LASTPIN (-5800 3600) BN 5
J 2
(-5788 3608);
DISPLAY 0.489362 (-5788 3608);
PAINT GREEN (-5788 3608);
FORCEPROP 2 LAST CDS_LIB mstr_standard
J 0
(-5850 3600);
DISPLAY 0.723404 (-5850 3600);
PAINT MONO (-5850 3600);
DISPLAY INVISIBLE (-5850 3600);
FORCEPROP 1 LAST BODY_TYPE PLUMBING
J 2
(-5850 3650);
DISPLAY 0.872340 (-5850 3650);
PAINT GREEN (-5850 3650);
DISPLAY INVISIBLE (-5850 3650);
FORCEPROP 1 LAST HDL_TAP TRUE
J 2
(-6175 3475);
DISPLAY 0.872340 (-6175 3475);
DISPLAY INVISIBLE (-6175 3475);
FORCEPROP 1 LAST PATH I293
J 2
(-5848 3600);
DISPLAY 0.872340 (-5848 3600);
PAINT GREEN (-5848 3600);
DISPLAY INVISIBLE (-5848 3600);
FORCEADD TAP..1
R 2
(-5850 3350);
FORCEPROP 3 LASTPIN (-5800 3350) SIG_NAME M_L_CPU0_SB_CA<2>
J 0
(-5790 3360);
DISPLAY 0.659574 (-5790 3360);
PAINT MONO (-5790 3360);
DISPLAY INVISIBLE (-5790 3360);
FORCEPROP 1 LASTPIN (-5800 3350) BN 2
J 2
(-5788 3358);
DISPLAY 0.489362 (-5788 3358);
PAINT GREEN (-5788 3358);
FORCEPROP 2 LAST CDS_LIB mstr_standard
J 0
(-5850 3350);
DISPLAY 0.723404 (-5850 3350);
PAINT MONO (-5850 3350);
DISPLAY INVISIBLE (-5850 3350);
FORCEPROP 1 LAST BODY_TYPE PLUMBING
J 2
(-5850 3400);
DISPLAY 0.872340 (-5850 3400);
PAINT GREEN (-5850 3400);
DISPLAY INVISIBLE (-5850 3400);
FORCEPROP 1 LAST HDL_TAP TRUE
J 2
(-6175 3225);
DISPLAY 0.872340 (-6175 3225);
DISPLAY INVISIBLE (-6175 3225);
FORCEPROP 1 LAST PATH I294
J 2
(-5848 3350);
DISPLAY 0.872340 (-5848 3350);
PAINT GREEN (-5848 3350);
DISPLAY INVISIBLE (-5848 3350);
FORCEADD TAP..1
R 2
(-5850 3550);
FORCEPROP 3 LASTPIN (-5800 3550) SIG_NAME M_L_CPU0_SA_CA<6>
J 0
(-5790 3560);
DISPLAY 0.659574 (-5790 3560);
PAINT MONO (-5790 3560);
DISPLAY INVISIBLE (-5790 3560);
FORCEPROP 1 LASTPIN (-5800 3550) BN 6
J 2
(-5788 3558);
DISPLAY 0.489362 (-5788 3558);
PAINT GREEN (-5788 3558);
FORCEPROP 2 LAST CDS_LIB mstr_standard
J 0
(-5850 3550);
DISPLAY 0.723404 (-5850 3550);
PAINT MONO (-5850 3550);
DISPLAY INVISIBLE (-5850 3550);
FORCEPROP 1 LAST BODY_TYPE PLUMBING
J 2
(-5850 3600);
DISPLAY 0.872340 (-5850 3600);
PAINT GREEN (-5850 3600);
DISPLAY INVISIBLE (-5850 3600);
FORCEPROP 1 LAST HDL_TAP TRUE
J 2
(-6175 3425);
DISPLAY 0.872340 (-6175 3425);
DISPLAY INVISIBLE (-6175 3425);
FORCEPROP 1 LAST PATH I295
J 2
(-5848 3550);
DISPLAY 0.872340 (-5848 3550);
PAINT GREEN (-5848 3550);
DISPLAY INVISIBLE (-5848 3550);
FORCEADD TAP..1
R 2
(-5850 3450);
FORCEPROP 3 LASTPIN (-5800 3450) SIG_NAME M_L_CPU0_SB_CA<0>
J 0
(-5790 3460);
DISPLAY 0.659574 (-5790 3460);
PAINT MONO (-5790 3460);
DISPLAY INVISIBLE (-5790 3460);
FORCEPROP 1 LASTPIN (-5800 3450) BN 0
J 2
(-5788 3458);
DISPLAY 0.489362 (-5788 3458);
PAINT GREEN (-5788 3458);
FORCEPROP 2 LAST CDS_LIB mstr_standard
J 0
(-5850 3450);
DISPLAY 0.723404 (-5850 3450);
PAINT MONO (-5850 3450);
DISPLAY INVISIBLE (-5850 3450);
FORCEPROP 1 LAST BODY_TYPE PLUMBING
J 2
(-5850 3500);
DISPLAY 0.872340 (-5850 3500);
PAINT GREEN (-5850 3500);
DISPLAY INVISIBLE (-5850 3500);
FORCEPROP 1 LAST HDL_TAP TRUE
J 2
(-6175 3325);
DISPLAY 0.872340 (-6175 3325);
DISPLAY INVISIBLE (-6175 3325);
FORCEPROP 1 LAST PATH I296
J 2
(-5848 3450);
DISPLAY 0.872340 (-5848 3450);
PAINT GREEN (-5848 3450);
DISPLAY INVISIBLE (-5848 3450);
FORCEADD TAP..1
R 2
(-5850 3400);
FORCEPROP 3 LASTPIN (-5800 3400) SIG_NAME M_L_CPU0_SB_CA<1>
J 0
(-5790 3410);
DISPLAY 0.659574 (-5790 3410);
PAINT MONO (-5790 3410);
DISPLAY INVISIBLE (-5790 3410);
FORCEPROP 1 LASTPIN (-5800 3400) BN 1
J 2
(-5788 3408);
DISPLAY 0.489362 (-5788 3408);
PAINT GREEN (-5788 3408);
FORCEPROP 2 LAST CDS_LIB mstr_standard
J 0
(-5850 3400);
DISPLAY 0.723404 (-5850 3400);
PAINT MONO (-5850 3400);
DISPLAY INVISIBLE (-5850 3400);
FORCEPROP 1 LAST BODY_TYPE PLUMBING
J 2
(-5850 3450);
DISPLAY 0.872340 (-5850 3450);
PAINT GREEN (-5850 3450);
DISPLAY INVISIBLE (-5850 3450);
FORCEPROP 1 LAST HDL_TAP TRUE
J 2
(-6175 3275);
DISPLAY 0.872340 (-6175 3275);
DISPLAY INVISIBLE (-6175 3275);
FORCEPROP 1 LAST PATH I297
J 2
(-5848 3400);
DISPLAY 0.872340 (-5848 3400);
PAINT GREEN (-5848 3400);
DISPLAY INVISIBLE (-5848 3400);
FORCEADD TAP..1
R 2
(-5850 3200);
FORCEPROP 3 LASTPIN (-5800 3200) SIG_NAME M_L_CPU0_SB_CA<5>
J 0
(-5790 3210);
DISPLAY 0.659574 (-5790 3210);
PAINT MONO (-5790 3210);
DISPLAY INVISIBLE (-5790 3210);
FORCEPROP 1 LASTPIN (-5800 3200) BN 5
J 2
(-5788 3208);
DISPLAY 0.489362 (-5788 3208);
PAINT GREEN (-5788 3208);
FORCEPROP 2 LAST CDS_LIB mstr_standard
J 0
(-5850 3200);
DISPLAY 0.723404 (-5850 3200);
PAINT MONO (-5850 3200);
DISPLAY INVISIBLE (-5850 3200);
FORCEPROP 1 LAST BODY_TYPE PLUMBING
J 2
(-5850 3250);
DISPLAY 0.872340 (-5850 3250);
PAINT GREEN (-5850 3250);
DISPLAY INVISIBLE (-5850 3250);
FORCEPROP 1 LAST HDL_TAP TRUE
J 2
(-6175 3075);
DISPLAY 0.872340 (-6175 3075);
DISPLAY INVISIBLE (-6175 3075);
FORCEPROP 1 LAST PATH I298
J 2
(-5848 3200);
DISPLAY 0.872340 (-5848 3200);
PAINT GREEN (-5848 3200);
DISPLAY INVISIBLE (-5848 3200);
FORCEADD TAP..1
R 2
(-5850 3300);
FORCEPROP 3 LASTPIN (-5800 3300) SIG_NAME M_L_CPU0_SB_CA<3>
J 0
(-5790 3310);
DISPLAY 0.659574 (-5790 3310);
PAINT MONO (-5790 3310);
DISPLAY INVISIBLE (-5790 3310);
FORCEPROP 1 LASTPIN (-5800 3300) BN 3
J 2
(-5788 3308);
DISPLAY 0.489362 (-5788 3308);
PAINT GREEN (-5788 3308);
FORCEPROP 2 LAST CDS_LIB mstr_standard
J 0
(-5850 3300);
DISPLAY 0.723404 (-5850 3300);
PAINT MONO (-5850 3300);
DISPLAY INVISIBLE (-5850 3300);
FORCEPROP 1 LAST BODY_TYPE PLUMBING
J 2
(-5850 3350);
DISPLAY 0.872340 (-5850 3350);
PAINT GREEN (-5850 3350);
DISPLAY INVISIBLE (-5850 3350);
FORCEPROP 1 LAST HDL_TAP TRUE
J 2
(-6175 3175);
DISPLAY 0.872340 (-6175 3175);
DISPLAY INVISIBLE (-6175 3175);
FORCEPROP 1 LAST PATH I299
J 2
(-5848 3300);
DISPLAY 0.872340 (-5848 3300);
PAINT GREEN (-5848 3300);
DISPLAY INVISIBLE (-5848 3300);
FORCEADD TAP..1
R 2
(-5850 3250);
FORCEPROP 3 LASTPIN (-5800 3250) SIG_NAME M_L_CPU0_SB_CA<4>
J 0
(-5790 3260);
DISPLAY 0.659574 (-5790 3260);
PAINT MONO (-5790 3260);
DISPLAY INVISIBLE (-5790 3260);
FORCEPROP 1 LASTPIN (-5800 3250) BN 4
J 2
(-5788 3258);
DISPLAY 0.489362 (-5788 3258);
PAINT GREEN (-5788 3258);
FORCEPROP 2 LAST CDS_LIB mstr_standard
J 0
(-5850 3250);
DISPLAY 0.723404 (-5850 3250);
PAINT MONO (-5850 3250);
DISPLAY INVISIBLE (-5850 3250);
FORCEPROP 1 LAST BODY_TYPE PLUMBING
J 2
(-5850 3300);
DISPLAY 0.872340 (-5850 3300);
PAINT GREEN (-5850 3300);
DISPLAY INVISIBLE (-5850 3300);
FORCEPROP 1 LAST HDL_TAP TRUE
J 2
(-6175 3125);
DISPLAY 0.872340 (-6175 3125);
DISPLAY INVISIBLE (-6175 3125);
FORCEPROP 1 LAST PATH I300
J 2
(-5848 3250);
DISPLAY 0.872340 (-5848 3250);
PAINT GREEN (-5848 3250);
DISPLAY INVISIBLE (-5848 3250);
FORCEADD TAP..1
R 2
(-5850 3150);
FORCEPROP 3 LASTPIN (-5800 3150) SIG_NAME M_L_CPU0_SB_CA<6>
J 0
(-5790 3160);
DISPLAY 0.659574 (-5790 3160);
PAINT MONO (-5790 3160);
DISPLAY INVISIBLE (-5790 3160);
FORCEPROP 1 LASTPIN (-5800 3150) BN 6
J 2
(-5788 3158);
DISPLAY 0.489362 (-5788 3158);
PAINT GREEN (-5788 3158);
FORCEPROP 2 LAST CDS_LIB mstr_standard
J 0
(-5850 3150);
DISPLAY 0.723404 (-5850 3150);
PAINT MONO (-5850 3150);
DISPLAY INVISIBLE (-5850 3150);
FORCEPROP 1 LAST BODY_TYPE PLUMBING
J 2
(-5850 3200);
DISPLAY 0.872340 (-5850 3200);
PAINT GREEN (-5850 3200);
DISPLAY INVISIBLE (-5850 3200);
FORCEPROP 1 LAST HDL_TAP TRUE
J 2
(-6175 3025);
DISPLAY 0.872340 (-6175 3025);
DISPLAY INVISIBLE (-6175 3025);
FORCEPROP 1 LAST PATH I301
J 2
(-5848 3150);
DISPLAY 0.872340 (-5848 3150);
PAINT GREEN (-5848 3150);
DISPLAY INVISIBLE (-5848 3150);
FORCEADD OFFPAGE..2
R 2
(-6450 3875);
FORCEPROP 2 LAST $XR0 97 
J 0
(-6674 3875);
DISPLAY 0.638298 (-6674 3875);
PAINT MONO (-6674 3875);
FORCEPROP 2 LAST CDS_LIB standard
J 0
(-6450 3875);
DISPLAY INVISIBLE (-6450 3875);
FORCEPROP 1 LAST OFFPAGE TRUE
J 2
(-6775 3750);
DISPLAY 0.872340 (-6775 3750);
PAINT GREEN (-6775 3750);
DISPLAY INVISIBLE (-6775 3750);
FORCEPROP 1 LAST COMMENT_BODY TRUE
J 2
(-6405 3780);
DISPLAY 0.872340 (-6405 3780);
PAINT GREEN (-6405 3780);
DISPLAY INVISIBLE (-6405 3780);
FORCEPROP 2 LAST PATH I302
J 0
(-6700 3925);
DISPLAY 1.021277 (-6700 3925);
DISPLAY INVISIBLE (-6700 3925);
FORCEADD OFFPAGE..2
R 2
(-6450 3475);
FORCEPROP 2 LAST $XR0 97 
J 0
(-6674 3475);
DISPLAY 0.638298 (-6674 3475);
PAINT MONO (-6674 3475);
FORCEPROP 2 LAST CDS_LIB standard
J 0
(-6450 3475);
DISPLAY INVISIBLE (-6450 3475);
FORCEPROP 1 LAST OFFPAGE TRUE
J 2
(-6775 3350);
DISPLAY 0.872340 (-6775 3350);
PAINT GREEN (-6775 3350);
DISPLAY INVISIBLE (-6775 3350);
FORCEPROP 1 LAST COMMENT_BODY TRUE
J 2
(-6405 3380);
DISPLAY 0.872340 (-6405 3380);
PAINT GREEN (-6405 3380);
DISPLAY INVISIBLE (-6405 3380);
FORCEPROP 2 LAST PATH I303
J 0
(-6700 3525);
DISPLAY 1.021277 (-6700 3525);
DISPLAY INVISIBLE (-6700 3525);
FORCEADD OFFPAGE..2
R 2
(-6450 3000);
FORCEPROP 2 LAST $XR0 97 
J 0
(-6674 3000);
DISPLAY 0.638298 (-6674 3000);
PAINT MONO (-6674 3000);
FORCEPROP 2 LAST CDS_LIB standard
J 0
(-6450 3000);
DISPLAY INVISIBLE (-6450 3000);
FORCEPROP 1 LAST OFFPAGE TRUE
J 2
(-6775 2875);
DISPLAY 0.872340 (-6775 2875);
PAINT GREEN (-6775 2875);
DISPLAY INVISIBLE (-6775 2875);
FORCEPROP 1 LAST COMMENT_BODY TRUE
J 2
(-6405 2905);
DISPLAY 0.872340 (-6405 2905);
PAINT GREEN (-6405 2905);
DISPLAY INVISIBLE (-6405 2905);
FORCEPROP 2 LAST PATH I304
J 0
(-6700 3050);
DISPLAY 1.021277 (-6700 3050);
DISPLAY INVISIBLE (-6700 3050);
FORCEADD OFFPAGE..2
R 2
(-6450 2950);
FORCEPROP 2 LAST $XR0 97 
J 0
(-6674 2950);
DISPLAY 0.638298 (-6674 2950);
PAINT MONO (-6674 2950);
FORCEPROP 2 LAST CDS_LIB standard
J 0
(-6450 2950);
DISPLAY INVISIBLE (-6450 2950);
FORCEPROP 1 LAST OFFPAGE TRUE
J 2
(-6775 2825);
DISPLAY 0.872340 (-6775 2825);
PAINT GREEN (-6775 2825);
DISPLAY INVISIBLE (-6775 2825);
FORCEPROP 1 LAST COMMENT_BODY TRUE
J 2
(-6405 2855);
DISPLAY 0.872340 (-6405 2855);
PAINT GREEN (-6405 2855);
DISPLAY INVISIBLE (-6405 2855);
FORCEPROP 2 LAST PATH I305
J 0
(-6700 3000);
DISPLAY 1.021277 (-6700 3000);
DISPLAY INVISIBLE (-6700 3000);
FORCEADD OFFPAGE..2
R 2
(-6450 2850);
FORCEPROP 2 LAST $XR0 97 
J 0
(-6674 2850);
DISPLAY 0.638298 (-6674 2850);
PAINT MONO (-6674 2850);
FORCEPROP 2 LAST CDS_LIB standard
J 0
(-6450 2850);
DISPLAY INVISIBLE (-6450 2850);
FORCEPROP 1 LAST OFFPAGE TRUE
J 2
(-6775 2725);
DISPLAY 0.872340 (-6775 2725);
PAINT GREEN (-6775 2725);
DISPLAY INVISIBLE (-6775 2725);
FORCEPROP 1 LAST COMMENT_BODY TRUE
J 2
(-6405 2755);
DISPLAY 0.872340 (-6405 2755);
PAINT GREEN (-6405 2755);
DISPLAY INVISIBLE (-6405 2755);
FORCEPROP 2 LAST PATH I306
J 0
(-6700 2900);
DISPLAY 1.021277 (-6700 2900);
DISPLAY INVISIBLE (-6700 2900);
FORCEADD OFFPAGE..5
(-6450 2600);
FORCEPROP 2 LAST $XR0 97 
J 0
(-6674 2600);
DISPLAY 0.638298 (-6674 2600);
PAINT MONO (-6674 2600);
FORCEPROP 2 LAST CDS_LIB mstr_standard
J 0
(-6450 2600);
DISPLAY INVISIBLE (-6450 2600);
FORCEPROP 1 LAST OFFPAGE TRUE
J 0
(-6125 2475);
DISPLAY 0.872340 (-6125 2475);
PAINT GREEN (-6125 2475);
DISPLAY INVISIBLE (-6125 2475);
FORCEPROP 1 LAST COMMENT_BODY TRUE
J 0
(-6350 2525);
DISPLAY 0.872340 (-6350 2525);
PAINT GREEN (-6350 2525);
DISPLAY INVISIBLE (-6350 2525);
FORCEPROP 2 LAST PATH I307
J 0
(-6700 2650);
DISPLAY 1.021277 (-6700 2650);
DISPLAY INVISIBLE (-6700 2650);
FORCEADD OFFPAGE..1
(-6450 2700);
FORCEPROP 2 LAST $XR0 97 
J 0
(-6701 2700);
DISPLAY 0.638298 (-6701 2700);
PAINT MONO (-6701 2700);
FORCEPROP 2 LAST CDS_LIB standard
J 0
(-6450 2700);
DISPLAY INVISIBLE (-6450 2700);
FORCEPROP 1 LAST OFFPAGE TRUE
J 0
(-6125 2575);
DISPLAY 0.872340 (-6125 2575);
PAINT GREEN (-6125 2575);
DISPLAY INVISIBLE (-6125 2575);
FORCEPROP 1 LAST COMMENT_BODY TRUE
J 0
(-6325 2600);
DISPLAY 0.872340 (-6325 2600);
PAINT GREEN (-6325 2600);
DISPLAY INVISIBLE (-6325 2600);
FORCEPROP 2 LAST PATH I308
J 0
(-6725 2750);
DISPLAY 1.021277 (-6725 2750);
DISPLAY INVISIBLE (-6725 2750);
FORCEADD OFFPAGE..2
R 2
(-6450 2800);
FORCEPROP 2 LAST $XR0 97 
J 0
(-6674 2800);
DISPLAY 0.638298 (-6674 2800);
PAINT MONO (-6674 2800);
FORCEPROP 2 LAST CDS_LIB standard
J 0
(-6450 2800);
DISPLAY INVISIBLE (-6450 2800);
FORCEPROP 1 LAST OFFPAGE TRUE
J 2
(-6775 2675);
DISPLAY 0.872340 (-6775 2675);
PAINT GREEN (-6775 2675);
DISPLAY INVISIBLE (-6775 2675);
FORCEPROP 1 LAST COMMENT_BODY TRUE
J 2
(-6405 2705);
DISPLAY 0.872340 (-6405 2705);
PAINT GREEN (-6405 2705);
DISPLAY INVISIBLE (-6405 2705);
FORCEPROP 2 LAST PATH I309
J 0
(-6700 2850);
DISPLAY 1.021277 (-6700 2850);
DISPLAY INVISIBLE (-6700 2850);
FORCEADD OFFPAGE..2
R 2
(-6450 2500);
FORCEPROP 2 LAST $XR0 97 
J 0
(-6674 2500);
DISPLAY 0.638298 (-6674 2500);
PAINT MONO (-6674 2500);
FORCEPROP 2 LAST CDS_LIB standard
J 0
(-6450 2500);
DISPLAY INVISIBLE (-6450 2500);
FORCEPROP 1 LAST OFFPAGE TRUE
J 2
(-6775 2375);
DISPLAY 0.872340 (-6775 2375);
PAINT GREEN (-6775 2375);
DISPLAY INVISIBLE (-6775 2375);
FORCEPROP 1 LAST COMMENT_BODY TRUE
J 2
(-6405 2405);
DISPLAY 0.872340 (-6405 2405);
PAINT GREEN (-6405 2405);
DISPLAY INVISIBLE (-6405 2405);
FORCEPROP 2 LAST PATH I310
J 0
(-6700 2550);
DISPLAY 1.021277 (-6700 2550);
DISPLAY INVISIBLE (-6700 2550);
FORCEADD OFFPAGE..2
R 2
(-6450 2450);
FORCEPROP 2 LAST $XR0 97 
J 0
(-6674 2450);
DISPLAY 0.638298 (-6674 2450);
PAINT MONO (-6674 2450);
FORCEPROP 2 LAST CDS_LIB standard
J 0
(-6450 2450);
DISPLAY INVISIBLE (-6450 2450);
FORCEPROP 1 LAST OFFPAGE TRUE
J 2
(-6775 2325);
DISPLAY 0.872340 (-6775 2325);
PAINT GREEN (-6775 2325);
DISPLAY INVISIBLE (-6775 2325);
FORCEPROP 1 LAST COMMENT_BODY TRUE
J 2
(-6405 2355);
DISPLAY 0.872340 (-6405 2355);
PAINT GREEN (-6405 2355);
DISPLAY INVISIBLE (-6405 2355);
FORCEPROP 2 LAST PATH I311
J 0
(-6700 2500);
DISPLAY 1.021277 (-6700 2500);
DISPLAY INVISIBLE (-6700 2500);
FORCEADD OFFPAGE..1
(-6450 2350);
FORCEPROP 2 LAST $XR0 97 
J 0
(-6701 2350);
DISPLAY 0.638298 (-6701 2350);
PAINT MONO (-6701 2350);
FORCEPROP 2 LAST CDS_LIB standard
J 0
(-6450 2350);
DISPLAY INVISIBLE (-6450 2350);
FORCEPROP 1 LAST OFFPAGE TRUE
J 0
(-6125 2225);
DISPLAY 0.872340 (-6125 2225);
PAINT GREEN (-6125 2225);
DISPLAY INVISIBLE (-6125 2225);
FORCEPROP 1 LAST COMMENT_BODY TRUE
J 0
(-6325 2250);
DISPLAY 0.872340 (-6325 2250);
PAINT GREEN (-6325 2250);
DISPLAY INVISIBLE (-6325 2250);
FORCEPROP 2 LAST PATH I312
J 0
(-6725 2400);
DISPLAY 1.021277 (-6725 2400);
DISPLAY INVISIBLE (-6725 2400);
FORCEADD OFFPAGE..5
(-6450 2250);
FORCEPROP 2 LAST $XR0 97 
J 0
(-6674 2250);
DISPLAY 0.638298 (-6674 2250);
PAINT MONO (-6674 2250);
FORCEPROP 2 LAST CDS_LIB standard
J 0
(-6450 2250);
DISPLAY INVISIBLE (-6450 2250);
FORCEPROP 1 LAST OFFPAGE TRUE
J 0
(-6125 2125);
DISPLAY 0.872340 (-6125 2125);
PAINT GREEN (-6125 2125);
DISPLAY INVISIBLE (-6125 2125);
FORCEPROP 1 LAST COMMENT_BODY TRUE
J 0
(-6350 2175);
DISPLAY 0.872340 (-6350 2175);
PAINT GREEN (-6350 2175);
DISPLAY INVISIBLE (-6350 2175);
FORCEPROP 2 LAST PATH I313
J 0
(-6700 2300);
DISPLAY 1.021277 (-6700 2300);
DISPLAY INVISIBLE (-6700 2300);
FORCEADD Q_RES..1
(-6775 2150);
FORCEPROP 1 LAST LOCATION R386
J 0
(-7100 2150);
DISPLAY 0.489362 (-7100 2150);
PAINT SKYBLUE (-7100 2150);
FORCEPROP 0 LAST $SEC 1
J 0
(-6950 2200);
DISPLAY 0.680851 (-6950 2200);
PAINT MONO (-6950 2200);
DISPLAY INVISIBLE (-6950 2200);
FORCEPROP 0 LAST CDS_SEC 1
J 0
(-6950 2200);
DISPLAY 1.021277 (-6950 2200);
DISPLAY INVISIBLE (-6950 2200);
FORCEPROP 1 LASTPIN (-6875 2150) $PN 1
J 0
(-6863 2162);
DISPLAY 0.489362 (-6863 2162);
PAINT MONO (-6863 2162);
FORCEPROP 1 LASTPIN (-6675 2150) $PN 2
J 0
(-6713 2162);
DISPLAY 0.489362 (-6713 2162);
PAINT MONO (-6713 2162);
FORCEPROP 1 LAST PACK_TYPE 0402LF
J 0
(-7100 2125);
DISPLAY 0.489362 (-7100 2125);
PAINT SKYBLUE (-7100 2125);
FORCEPROP 1 LAST TOLERANCE 1%
J 0
(-6500 2150);
DISPLAY 0.489362 (-6500 2150);
PAINT SKYBLUE (-6500 2150);
FORCEPROP 1 LAST VALUE 15
J 2
(-6450 2150);
DISPLAY 0.489362 (-6450 2150);
PAINT SKYBLUE (-6450 2150);
FORCEPROP 1 LAST MATERIAL CHIP
J 0
(-6900 2275);
DISPLAY 0.638298 (-6900 2275);
PAINT SKYBLUE (-6900 2275);
DISPLAY INVISIBLE (-6900 2275);
FORCEPROP 1 LAST WATTAGE 1/16W
J 2
(-6550 2275);
DISPLAY 0.638298 (-6550 2275);
PAINT SKYBLUE (-6550 2275);
DISPLAY INVISIBLE (-6550 2275);
FORCEPROP 2 LAST CDS_LIB pure_quanta
J 0
(-6775 2150);
DISPLAY INVISIBLE (-6775 2150);
FORCEPROP 1 LAST PATH I314
J 0
(-6825 2300);
DISPLAY 0.978723 (-6825 2300);
PAINT WHITE (-6825 2300);
DISPLAY INVISIBLE (-6825 2300);
FORCEPROP 1 LAST PART_NUMBER CS01502FB03
J 0
(-6625 2125);
DISPLAY 0.489362 (-6625 2125);
PAINT SKYBLUE (-6625 2125);
DISPLAY INVISIBLE (-6625 2125);
FORCEADD OFFPAGE..1
(-7650 2150);
FORCEPROP 2 LAST $XR0 97 
J 0
(-7871 2150);
DISPLAY 0.638298 (-7871 2150);
PAINT MONO (-7871 2150);
FORCEPROP 2 LAST CDS_LIB mstr_standard
J 0
(-7650 2150);
DISPLAY INVISIBLE (-7650 2150);
FORCEPROP 1 LAST OFFPAGE TRUE
J 0
(-7325 2025);
DISPLAY 0.872340 (-7325 2025);
PAINT GREEN (-7325 2025);
DISPLAY INVISIBLE (-7325 2025);
FORCEPROP 1 LAST COMMENT_BODY TRUE
J 0
(-7525 2050);
DISPLAY 0.872340 (-7525 2050);
PAINT GREEN (-7525 2050);
DISPLAY INVISIBLE (-7525 2050);
FORCEPROP 2 LAST PATH I315
J 0
(-7900 2200);
DISPLAY 1.021277 (-7900 2200);
DISPLAY INVISIBLE (-7900 2200);
FORCEADD OFFPAGE..5
(-6450 2050);
FORCEPROP 2 LAST $XR0 97 
J 0
(-6674 2050);
DISPLAY 0.638298 (-6674 2050);
PAINT MONO (-6674 2050);
FORCEPROP 2 LAST CDS_LIB standard
J 0
(-6450 2050);
DISPLAY INVISIBLE (-6450 2050);
FORCEPROP 1 LAST OFFPAGE TRUE
J 0
(-6125 1925);
DISPLAY 0.872340 (-6125 1925);
PAINT GREEN (-6125 1925);
DISPLAY INVISIBLE (-6125 1925);
FORCEPROP 1 LAST COMMENT_BODY TRUE
J 0
(-6350 1975);
DISPLAY 0.872340 (-6350 1975);
PAINT GREEN (-6350 1975);
DISPLAY INVISIBLE (-6350 1975);
FORCEPROP 2 LAST PATH I316
J 0
(-6700 2100);
DISPLAY 1.021277 (-6700 2100);
DISPLAY INVISIBLE (-6700 2100);
FORCEADD CAD_NOTE..1
(-7800 2575);
FORCEPROP 0 LAST L1 R1982 PLACE CLOSE TO CPU < 25MM
J 0
(-7950 2450);
DISPLAY 0.617021 (-7950 2450);
PAINT WHITE (-7950 2450);
FORCEPROP 2 LAST CDS_LIB pure_quanta_power
J 0
(-7800 2575);
DISPLAY INVISIBLE (-7800 2575);
FORCEPROP 1 LAST COMMENT_BODY TRUE
J 0
(-7775 2675);
DISPLAY 0.574468 (-7775 2675);
PAINT WHITE (-7775 2675);
DISPLAY INVISIBLE (-7775 2675);
FORCEADD QUANTA_TITLE_BLOCK_C..1
(0 0);
FORCEPROP 0 LAST CDS_CON_LAST_MODIFIED Thu Sep 14 16:11:51 2023
J 0
(-1885 15);
DISPLAY INVISIBLE (-1885 15);
FORCEPROP 1 LAST CUSTOM_TXT_CDS <CON_LAST_MODIFIED>
J 0
(-1885 15);
DISPLAY 0.978723 (-1885 15);
FORCEPROP 2 LAST CUSTOM_TXT_CDS <XR_PAGE_TITLE>
J 0
(-7890 5250);
DISPLAY 0.638298 (-7890 5250);
PAINT PINK (-7890 5250);
DISPLAY INVISIBLE (-7890 5250);
FORCEPROP 1 LAST CUSTOM_TXT_CDS <NAME_2>
J 0
(-3175 50);
FORCEPROP 1 LAST CUSTOM_TXT_CDS <NAME_1>
J 0
(-3175 175);
FORCEPROP 1 LAST CUSTOM_TXT_CDS <Q_NUMBER>
J 0
(-1403 103);
DISPLAY 1.212766 (-1403 103);
FORCEPROP 1 LAST CUSTOM_TXT_CDS <Q_PROJ>
J 0
(-2382 102);
DISPLAY 1.212766 (-2382 102);
FORCEPROP 1 LAST CUSTOM_TXT_CDS <Q_REV>
J 0
(-184 103);
DISPLAY 1.212766 (-184 103);
FORCEPROP 1 LAST CUSTOM_TXT_CDS <CON_PAGE_NUM> OF <CON_TOTAL_PAGES>
J 0
(-446 18);
DISPLAY 0.978723 (-446 18);
FORCEPROP 1 LAST Q_TITLE CPU0 DDR CHL
J 0
(-9350 25);
DISPLAY 2.446809 (-9350 25);
PAINT GREEN (-9350 25);
FORCEPROP 2 LAST PAGE_BORDER TRUE
J 0
(-7890 5250);
DISPLAY 0.638298 (-7890 5250);
PAINT PINK (-7890 5250);
DISPLAY INVISIBLE (-7890 5250);
FORCEPROP 2 LAST CDS_LIB pure_quanta
J 0
(0 0);
DISPLAY INVISIBLE (0 0);
FORCEPROP 1 LAST CDS_LMAN_SYM_OUTLINE -9475,6775,100,-125
J 0
(0 0);
DISPLAY 0.468085 (0 0);
PAINT GREEN (0 0);
DISPLAY INVISIBLE (0 0);
FORCEPROP 2 LAST CDS_XR_PAGE_TITLE CR-21 : @T6G_MB_LIB.T6G(SCH_1):PAGE21
J 0
(-7890 5250);
DISPLAY 0.638298 (-7890 5250);
PAINT PINK (-7890 5250);
DISPLAY INVISIBLE (-7890 5250);
FORCEPROP 1 LAST Q_DEPT BU9
J 1
(-3763 49);
DISPLAY 1.957447 (-3763 49);
PAINT GREEN (-3763 49);
DISPLAY INVISIBLE (-3763 49);
FORCEPROP 1 LAST COMMENT_BODY TRUE
J 0
(12 -13);
DISPLAY 0.978723 (12 -13);
PAINT GREEN (12 -13);
DISPLAY INVISIBLE (12 -13);
WIRE 17 -1 (-3175 5475)(-3175 5425);
WIRE 17 -1 (-3175 5525)(-3175 5475);
WIRE 17 -1 (-3175 5425)(-3175 5375);
WIRE 17 -1 (-3175 5375)(-3175 5325);
WIRE 17 -1 (-3175 5575)(-3175 5525);
WIRE 17 -1 (-3175 5675)(-3175 5575);
WIRE 17 -1 (-3175 5325)(-3175 5275);
WIRE 17 -1 (-3175 5275)(-3175 5225);
WIRE 17 -1 (-3175 5725)(-3175 5675);
WIRE 17 -1 (-3175 5775)(-3175 5725);
WIRE 17 -1 (-3175 5125)(-3175 5225);
WIRE 17 -1 (-3175 5075)(-3175 5125);
WIRE 17 -1 (-3175 5825)(-3175 5775);
WIRE 17 -1 (-3175 5875)(-3175 5825);
WIRE 17 -1 (-3175 5025)(-3175 5075);
WIRE 17 -1 (-3175 4975)(-3175 5025);
WIRE 17 -1 (-3175 5925)(-3175 5875);
WIRE 17 -1 (-3175 5975)(-3175 5925);
WIRE 17 -1 (-3175 4975)(-3175 4925);
WIRE 17 -1 (-3175 4925)(-3175 4875);
WIRE 17 -1 (-3175 6025)(-3175 5975);
WIRE 17 -1 (-3175 6025)(-2550 6025);
FORCEPROP 2 LAST SIG_NAME M_L_CPU0_SA_DQ<31:0>
J 2
(-2610 6035);
DISPLAY 0.489362 (-2610 6035);
WIRE 17 -1 (-3175 4875)(-3175 4825);
WIRE 17 -1 (-3175 4825)(-3175 4775);
WIRE 17 -1 (-3175 4775)(-3175 4675);
WIRE 17 -1 (-3175 4675)(-3175 4625);
WIRE 17 -1 (-3175 4625)(-3175 4575);
WIRE 17 -1 (-3175 4575)(-3175 4525);
WIRE 17 -1 (-3175 4475)(-3175 4525);
WIRE 17 -1 (-3175 4425)(-3175 4475);
WIRE 17 -1 (-3175 4375)(-3175 4425);
WIRE 17 -1 (-3175 4325)(-3175 4375);
WIRE 17 -1 (-3175 4225)(-2550 4225);
FORCEPROP 2 LAST SIG_NAME M_L_CPU0_SB_DQ<31:0>
J 2
(-2610 4235);
DISPLAY 0.489362 (-2610 4235);
WIRE 17 -1 (-3175 4225)(-3175 4175);
WIRE 17 -1 (-3175 4175)(-3175 4125);
WIRE 17 -1 (-3175 4125)(-3175 4075);
WIRE 17 -1 (-3175 4075)(-3175 4025);
WIRE 17 -1 (-3175 4025)(-3175 3975);
WIRE 17 -1 (-3175 3975)(-3175 3925);
WIRE 17 -1 (-3175 3925)(-3175 3875);
WIRE 17 -1 (-3175 3875)(-3175 3775);
WIRE 17 -1 (-3175 3775)(-3175 3725);
WIRE 17 -1 (-3175 3725)(-3175 3675);
WIRE 17 -1 (-3175 3675)(-3175 3625);
WIRE 17 -1 (-3175 3625)(-3175 3575);
WIRE 17 -1 (-3175 3575)(-3175 3525);
WIRE 17 -1 (-3175 3175)(-3175 3125);
WIRE 17 -1 (-3175 3175)(-3175 3225);
WIRE 17 -1 (-3175 3125)(-3175 3075);
WIRE 17 -1 (-3175 3075)(-3175 3025);
WIRE 17 -1 (-3175 3225)(-3175 3275);
WIRE 17 -1 (-3175 3275)(-3175 3325);
WIRE 17 -1 (-3175 3025)(-3175 2975);
WIRE 17 -1 (-3175 2975)(-3175 2875);
WIRE 17 -1 (-3175 3325)(-3175 3425);
WIRE 17 -1 (-3175 3475)(-3175 3425);
WIRE 17 -1 (-3175 2875)(-3175 2825);
WIRE 17 -1 (-3175 2825)(-3175 2775);
WIRE 17 -1 (-3175 3525)(-3175 3475);
WIRE 17 -1 (-3175 2775)(-3175 2725);
WIRE 17 -1 (-3175 2675)(-3175 2725);
WIRE 17 -1 (-3175 2625)(-3175 2675);
WIRE 17 -1 (-3175 2575)(-3175 2625);
WIRE 17 -1 (-3175 2525)(-3175 2575);
WIRE 17 -1 (-3175 2325)(-3175 2375);
WIRE 17 -1 (-3175 2325)(-3175 2275);
WIRE 17 -1 (-3175 2425)(-3175 2375);
WIRE 17 -1 (-3175 2425)(-3175 2450);
WIRE 17 -1 (-3175 2225)(-3175 2275);
WIRE 17 -1 (-3175 2175)(-3175 2225);
WIRE 17 -1 (-3175 2450)(-2675 2450);
FORCEPROP 2 LAST SIG_NAME M_L_CPU0_SA_CB<7:0>
J 2
(-2675 2460);
DISPLAY 0.489362 (-2675 2460);
WIRE 17 -1 (-3175 2125)(-3175 2175);
WIRE 17 -1 (-3175 2075)(-3175 2125);
WIRE 17 -1 (-3175 1975)(-3175 2000);
WIRE 17 -1 (-3175 1975)(-3175 1925);
WIRE 17 -1 (-3175 2000)(-2675 2000);
FORCEPROP 2 LAST SIG_NAME M_L_CPU0_SB_CB<7:0>
J 2
(-2675 2010);
DISPLAY 0.489362 (-2675 2010);
WIRE 17 -1 (-3175 1875)(-3175 1925);
WIRE 17 -1 (-3175 1875)(-3175 1825);
WIRE 17 -1 (-3175 1775)(-3175 1825);
WIRE 17 -1 (-3175 1725)(-3175 1775);
WIRE 17 -1 (-3175 1675)(-3175 1725);
WIRE 17 -1 (-3175 1625)(-3175 1675);
WIRE 17 -1 (-5700 6025)(-5700 5925);
WIRE 17 -1 (-5700 6025)(-6500 6025);
FORCEPROP 2 LAST SIG_NAME M_L_CPU0_SA_DQS_DP<9:0>
J 2
(-5935 6035);
DISPLAY 0.489362 (-5935 6035);
WIRE 17 -1 (-5700 5925)(-5700 5825);
WIRE 17 -1 (-5700 5825)(-5700 5725);
WIRE 17 -1 (-5700 5725)(-5700 5625);
WIRE 17 -1 (-5700 5525)(-5700 5625);
WIRE 17 -1 (-5700 5425)(-5700 5525);
WIRE 17 -1 (-5700 5325)(-5700 5425);
WIRE 17 -1 (-5700 5325)(-5700 5225);
WIRE 17 -1 (-5700 5225)(-5700 5125);
WIRE 17 -1 (-5900 5975)(-5900 5875);
FORCEPROP 2 LAST SIG_NAME M_L_CPU0_SA_DQS_DN<9:0>
J 2
(-5935 5985);
DISPLAY 0.489362 (-5935 5985);
WIRE 17 -1 (-5900 5875)(-5900 5775);
WIRE 17 -1 (-5900 5775)(-5900 5675);
WIRE 17 -1 (-5900 5675)(-5900 5575);
WIRE 17 -1 (-5900 5475)(-5900 5575);
WIRE 17 -1 (-5900 5375)(-5900 5475);
WIRE 17 -1 (-5900 5275)(-5900 5375);
WIRE 17 -1 (-5900 5275)(-5900 5175);
WIRE 17 -1 (-5900 5175)(-5900 5075);
WIRE 17 -1 (-5700 4975)(-5700 4875);
WIRE 17 -1 (-5700 4975)(-6500 4975);
FORCEPROP 2 LAST SIG_NAME M_L_CPU0_SB_DQS_DP<9:0>
J 2
(-5935 4985);
DISPLAY 0.489362 (-5935 4985);
WIRE 17 -1 (-5700 4875)(-5700 4775);
WIRE 17 -1 (-5700 4775)(-5700 4675);
WIRE 17 -1 (-5700 4675)(-5700 4575);
WIRE 17 -1 (-5700 4475)(-5700 4575);
WIRE 17 -1 (-5700 4375)(-5700 4475);
WIRE 17 -1 (-5700 4275)(-5700 4375);
WIRE 17 -1 (-5700 4275)(-5700 4175);
WIRE 17 -1 (-5700 4175)(-5700 4075);
WIRE 17 -1 (-5900 4925)(-5900 4825);
FORCEPROP 2 LAST SIG_NAME M_L_CPU0_SB_DQS_DN<9:0>
J 2
(-5935 4935);
DISPLAY 0.489362 (-5935 4935);
WIRE 17 -1 (-5900 4825)(-5900 4725);
WIRE 17 -1 (-5900 4725)(-5900 4625);
WIRE 17 -1 (-5900 4625)(-5900 4525);
WIRE 17 -1 (-5900 4425)(-5900 4525);
WIRE 17 -1 (-5900 4325)(-5900 4425);
WIRE 17 -1 (-5900 4225)(-5900 4325);
WIRE 17 -1 (-5900 4225)(-5900 4125);
WIRE 17 -1 (-5900 4125)(-5900 4025);
WIRE 17 -1 (-5900 3375)(-5900 3425);
WIRE 17 -1 (-5900 3325)(-5900 3375);
WIRE 17 -1 (-5900 3425)(-5900 3475);
WIRE 17 -1 (-5900 3475)(-6400 3475);
FORCEPROP 2 LAST SIG_NAME M_L_CPU0_SB_CA<6:0>
J 0
(-6400 3485);
DISPLAY 0.489362 (-6400 3485);
WIRE 17 -1 (-5900 3725)(-5900 3775);
WIRE 17 -1 (-5900 3675)(-5900 3725);
WIRE 17 -1 (-5900 3775)(-5900 3825);
WIRE 17 -1 (-5900 3825)(-5900 3875);
WIRE 17 -1 (-5900 3625)(-5900 3675);
WIRE 17 -1 (-5900 3575)(-5900 3625);
WIRE 17 -1 (-5900 3875)(-6400 3875);
FORCEPROP 2 LAST SIG_NAME M_L_CPU0_SA_CA<6:0>
J 0
(-6400 3885);
DISPLAY 0.489362 (-6400 3885);
WIRE 17 -1 (-5900 3275)(-5900 3325);
WIRE 17 -1 (-5900 3225)(-5900 3275);
WIRE 17 -1 (-5900 3175)(-5900 3225);
WIRE 17 -1 (-5900 5975)(-6500 5975);
WIRE 17 -1 (-5900 4925)(-6500 4925);
WIRE 16 -1 (-7600 2150)(-6875 2150);
FORCEPROP 2 LAST SIG_NAME M_L_CPU0_ALERT_N
J 0
(-7560 2160);
DISPLAY 0.489362 (-7560 2160);
WIRE 16 -1 (-6675 2150)(-5300 2150);
FORCEPROP 2 LAST SIG_NAME M_L_CPU0_ALERT_R_N
J 0
(-6385 2160);
DISPLAY 0.489362 (-6385 2160);
FORCEPROP 2 LASTPROP $XRERR UNIQUE?
J 0
(-6625 2160);
DISPLAY 0.638298 (-6625 2160);
PAINT MONO (-6625 2160);
DISPLAY INVISIBLE (-6625 2160);
WIRE 16 -1 (-6400 1200)(-5300 1200);
FORCEPROP 2 LAST SIG_NAME TP_M_L_CPU0_SA_TEST39L
J 0
(-6385 1210);
DISPLAY 0.489362 (-6385 1210);
FORCEPROP 2 LASTPROP $XRERR UNIQUE?
J 0
(-6640 1200);
DISPLAY 0.638298 (-6640 1200);
PAINT MONO (-6640 1200);
DISPLAY INVISIBLE (-6640 1200);
WIRE 16 -1 (-6400 3000)(-5300 3000);
FORCEPROP 2 LAST SIG_NAME M_L_CPU0_CLK_DP<0>
J 0
(-6400 3010);
DISPLAY 0.489362 (-6400 3010);
WIRE 16 -1 (-6400 2950)(-5300 2950);
FORCEPROP 2 LAST SIG_NAME M_L_CPU0_CLK_DN<0>
J 0
(-6400 2960);
DISPLAY 0.489362 (-6400 2960);
WIRE 16 -1 (-6400 2850)(-5300 2850);
FORCEPROP 2 LAST SIG_NAME M_L_CPU0_SA_CS_N<0>
J 0
(-6400 2860);
DISPLAY 0.489362 (-6400 2860);
WIRE 16 -1 (-6400 2600)(-5300 2600);
FORCEPROP 2 LAST SIG_NAME M_L_CPU0_SA_PAR
J 0
(-6400 2610);
DISPLAY 0.489362 (-6400 2610);
WIRE 16 -1 (-6400 2700)(-5300 2700);
FORCEPROP 2 LAST SIG_NAME M_L_CPU0_SA_RSP<0>
J 0
(-6400 2710);
DISPLAY 0.489362 (-6400 2710);
WIRE 16 -1 (-6400 2800)(-5300 2800);
FORCEPROP 2 LAST SIG_NAME M_L_CPU0_SA_CS_N<1>
J 0
(-6400 2810);
DISPLAY 0.489362 (-6400 2810);
WIRE 16 -1 (-6400 2500)(-5300 2500);
FORCEPROP 2 LAST SIG_NAME M_L_CPU0_SB_CS_N<0>
J 0
(-6400 2510);
DISPLAY 0.489362 (-6400 2510);
WIRE 16 -1 (-6400 2450)(-5300 2450);
FORCEPROP 2 LAST SIG_NAME M_L_CPU0_SB_CS_N<1>
J 0
(-6400 2460);
DISPLAY 0.489362 (-6400 2460);
WIRE 16 -1 (-6400 2350)(-5300 2350);
FORCEPROP 2 LAST SIG_NAME M_L_CPU0_SB_RSP<0>
J 0
(-6400 2360);
DISPLAY 0.489362 (-6400 2360);
WIRE 16 -1 (-6400 2250)(-5300 2250);
FORCEPROP 2 LAST SIG_NAME M_L_CPU0_SB_PAR
J 0
(-6400 2260);
DISPLAY 0.489362 (-6400 2260);
WIRE 16 -1 (-6400 2050)(-5300 2050);
FORCEPROP 2 LAST SIG_NAME M_L_CPU0_RESET_N
J 0
(-6400 2060);
DISPLAY 0.489362 (-6400 2060);
WIRE 16 -1 (-5800 3800)(-5300 3800);
WIRE 16 -1 (-5800 3450)(-5300 3450);
WIRE 16 -1 (-5800 3850)(-5300 3850);
WIRE 16 -1 (-5800 3150)(-5300 3150);
WIRE 16 -1 (-5800 3550)(-5300 3550);
WIRE 16 -1 (-5800 3200)(-5300 3200);
WIRE 16 -1 (-5800 3600)(-5300 3600);
WIRE 16 -1 (-5800 3250)(-5300 3250);
WIRE 16 -1 (-5800 3650)(-5300 3650);
WIRE 16 -1 (-5800 3300)(-5300 3300);
WIRE 16 -1 (-5800 3700)(-5300 3700);
WIRE 16 -1 (-5800 3350)(-5300 3350);
WIRE 16 -1 (-5800 3750)(-5300 3750);
WIRE 16 -1 (-5800 3400)(-5300 3400);
WIRE 16 -1 (-5800 4000)(-5300 4000);
WIRE 16 -1 (-5600 4050)(-5300 4050);
WIRE 16 -1 (-5800 4100)(-5300 4100);
WIRE 16 -1 (-5800 4200)(-5300 4200);
WIRE 16 -1 (-5800 4300)(-5300 4300);
WIRE 16 -1 (-5800 4400)(-5300 4400);
WIRE 16 -1 (-5800 4500)(-5300 4500);
WIRE 16 -1 (-5800 5050)(-5300 5050);
WIRE 16 -1 (-5800 4600)(-5300 4600);
WIRE 16 -1 (-5800 4700)(-5300 4700);
WIRE 16 -1 (-5800 4800)(-5300 4800);
WIRE 16 -1 (-5800 4900)(-5300 4900);
WIRE 16 -1 (-5600 4550)(-5300 4550);
WIRE 16 -1 (-5600 4150)(-5300 4150);
WIRE 16 -1 (-5600 4250)(-5300 4250);
WIRE 16 -1 (-5600 4350)(-5300 4350);
WIRE 16 -1 (-5600 4450)(-5300 4450);
WIRE 16 -1 (-5600 5100)(-5300 5100);
WIRE 16 -1 (-5600 4650)(-5300 4650);
WIRE 16 -1 (-5600 4750)(-5300 4750);
WIRE 16 -1 (-5600 4850)(-5300 4850);
WIRE 16 -1 (-5600 4950)(-5300 4950);
WIRE 16 -1 (-5800 5150)(-5300 5150);
WIRE 16 -1 (-5800 5250)(-5300 5250);
WIRE 16 -1 (-5800 5350)(-5300 5350);
WIRE 16 -1 (-5800 5450)(-5300 5450);
WIRE 16 -1 (-5800 5550)(-5300 5550);
WIRE 16 -1 (-5800 5650)(-5300 5650);
WIRE 16 -1 (-5800 5750)(-5300 5750);
WIRE 16 -1 (-5800 5850)(-5300 5850);
WIRE 16 -1 (-5800 5950)(-5300 5950);
WIRE 16 -1 (-5600 5200)(-5300 5200);
WIRE 16 -1 (-5600 5300)(-5300 5300);
WIRE 16 -1 (-5600 5400)(-5300 5400);
WIRE 16 -1 (-5600 5500)(-5300 5500);
WIRE 16 -1 (-5600 5600)(-5300 5600);
WIRE 16 -1 (-5600 5700)(-5300 5700);
WIRE 16 -1 (-5600 5800)(-5300 5800);
WIRE 16 -1 (-5600 5900)(-5300 5900);
WIRE 16 -1 (-5600 6000)(-5300 6000);
WIRE 16 -1 (-3700 1600)(-3275 1600);
WIRE 16 -1 (-3700 1650)(-3275 1650);
WIRE 16 -1 (-3700 1700)(-3275 1700);
WIRE 16 -1 (-3700 1750)(-3275 1750);
WIRE 16 -1 (-3700 1800)(-3275 1800);
WIRE 16 -1 (-3700 1850)(-3275 1850);
WIRE 16 -1 (-3700 1900)(-3275 1900);
WIRE 16 -1 (-3700 1950)(-3275 1950);
WIRE 16 -1 (-3700 2350)(-3275 2350);
WIRE 16 -1 (-3700 2400)(-3275 2400);
WIRE 16 -1 (-3700 2600)(-3275 2600);
WIRE 16 -1 (-3700 2650)(-3275 2650);
WIRE 16 -1 (-3700 2700)(-3275 2700);
WIRE 16 -1 (-3700 2750)(-3275 2750);
WIRE 16 -1 (-3700 2800)(-3275 2800);
WIRE 16 -1 (-3700 2850)(-3275 2850);
WIRE 16 -1 (-3700 2950)(-3275 2950);
WIRE 16 -1 (-3700 3000)(-3275 3000);
WIRE 16 -1 (-3700 2050)(-3275 2050);
WIRE 16 -1 (-3700 3050)(-3275 3050);
WIRE 16 -1 (-3700 2100)(-3275 2100);
WIRE 16 -1 (-3700 2500)(-3275 2500);
WIRE 16 -1 (-3700 2150)(-3275 2150);
WIRE 16 -1 (-3700 2550)(-3275 2550);
WIRE 16 -1 (-3700 2200)(-3275 2200);
WIRE 16 -1 (-3700 2250)(-3275 2250);
WIRE 16 -1 (-3700 2300)(-3275 2300);
WIRE 16 -1 (-3700 4050)(-3275 4050);
WIRE 16 -1 (-3700 3150)(-3275 3150);
WIRE 16 -1 (-3700 3200)(-3275 3200);
WIRE 16 -1 (-3700 3250)(-3275 3250);
WIRE 16 -1 (-3700 3300)(-3275 3300);
WIRE 16 -1 (-3700 3400)(-3275 3400);
WIRE 16 -1 (-3700 3450)(-3275 3450);
WIRE 16 -1 (-3700 3500)(-3275 3500);
WIRE 16 -1 (-3700 3550)(-3275 3550);
WIRE 16 -1 (-3700 3600)(-3275 3600);
WIRE 16 -1 (-3700 3700)(-3275 3700);
WIRE 16 -1 (-3700 3650)(-3275 3650);
WIRE 16 -1 (-3700 3750)(-3275 3750);
WIRE 16 -1 (-3700 3100)(-3275 3100);
WIRE 16 -1 (-3700 3850)(-3275 3850);
WIRE 16 -1 (-3700 3900)(-3275 3900);
WIRE 16 -1 (-3700 3950)(-3275 3950);
WIRE 16 -1 (-3700 4000)(-3275 4000);
WIRE 16 -1 (-3700 4850)(-3275 4850);
WIRE 16 -1 (-3700 4900)(-3275 4900);
WIRE 16 -1 (-3700 4300)(-3275 4300);
WIRE 16 -1 (-3700 4100)(-3275 4100);
WIRE 16 -1 (-3700 4350)(-3275 4350);
WIRE 16 -1 (-3700 4150)(-3275 4150);
WIRE 16 -1 (-3700 4200)(-3275 4200);
WIRE 16 -1 (-3700 4950)(-3275 4950);
WIRE 16 -1 (-3700 5000)(-3275 5000);
WIRE 16 -1 (-3700 4400)(-3275 4400);
WIRE 16 -1 (-3700 5050)(-3275 5050);
WIRE 16 -1 (-3700 4450)(-3275 4450);
WIRE 16 -1 (-3700 5100)(-3275 5100);
WIRE 16 -1 (-3700 4500)(-3275 4500);
WIRE 16 -1 (-3700 4550)(-3275 4550);
WIRE 16 -1 (-3700 4600)(-3275 4600);
WIRE 16 -1 (-3700 4650)(-3275 4650);
WIRE 16 -1 (-3700 4750)(-3275 4750);
WIRE 16 -1 (-3700 4800)(-3275 4800);
WIRE 16 -1 (-3700 5800)(-3275 5800);
WIRE 16 -1 (-3700 5450)(-3275 5450);
WIRE 16 -1 (-3700 5850)(-3275 5850);
WIRE 16 -1 (-3700 5900)(-3275 5900);
WIRE 16 -1 (-3700 5950)(-3275 5950);
WIRE 16 -1 (-3700 6000)(-3275 6000);
WIRE 16 -1 (-3700 5500)(-3275 5500);
WIRE 16 -1 (-3700 5200)(-3275 5200);
WIRE 16 -1 (-3700 5550)(-3275 5550);
WIRE 16 -1 (-3700 5250)(-3275 5250);
WIRE 16 -1 (-3700 5650)(-3275 5650);
WIRE 16 -1 (-3700 5300)(-3275 5300);
WIRE 16 -1 (-3700 5700)(-3275 5700);
WIRE 16 -1 (-3700 5350)(-3275 5350);
WIRE 16 -1 (-3700 5750)(-3275 5750);
WIRE 16 -1 (-3700 5400)(-3275 5400);
QUIT
